FILE_TYPE = MACRO_DRAWING;
SET COLOR_WIRE YELLOW;
SET COLOR_PROP ORANGE;
SET COLOR_DOT WHITE;
SET COLOR_ARC YELLOW;
SET COLOR_BODY GREEN;
SET COLOR_NOTE PURPLE;
SET PROP_DISPLAY VALUE;
SET PAGE_NUMBER P180;
FORCEADD UNIVERSAL_GND..1
(825 1550);
FORCEPROP 3 LASTPIN (825 1600) SIG_NAME GND\g
J 0
(835 1610);
DISPLAY 0.659574 (835 1610);
PAINT MONO (835 1610);
DISPLAY INVISIBLE (835 1610);
FORCEPROP 2 LAST CDS_LIB pure_quanta_power
J 0
(825 1550);
PAINT MONO (825 1550);
DISPLAY INVISIBLE (825 1550);
FORCEPROP 1 LAST PATH I1
J 0
(900 1550);
DISPLAY 0.872340 (900 1550);
PAINT AQUA (900 1550);
DISPLAY INVISIBLE (900 1550);
FORCEPROP 1 LAST HDL_POWER GND
J 1
(850 1475);
DISPLAY 0.872340 (850 1475);
PAINT GREEN (850 1475);
DISPLAY INVISIBLE (850 1475);
FORCEADD VCC_CORE..1
(5425 6350);
FORCEPROP 3 LASTPIN (5425 6300) SIG_NAME SW_P12V_STBY_PVDDIO_P0_FLT\g
J 0
(5435 6310);
DISPLAY 0.659574 (5435 6310);
PAINT MONO (5435 6310);
DISPLAY INVISIBLE (5435 6310);
FORCEPROP 1 LAST HDL_POWER SW_P12V_STBY_PVDDIO_P0_FLT
J 1
(5425 6400);
DISPLAY 0.489362 (5425 6400);
PAINT GREEN (5425 6400);
FORCEPROP 2 LAST CDS_LIB pure_quanta_power
J 0
(5425 6350);
DISPLAY INVISIBLE (5425 6350);
FORCEPROP 1 LAST PATH I100
J 0
(5475 6375);
DISPLAY 0.872340 (5475 6375);
PAINT AQUA (5475 6375);
DISPLAY INVISIBLE (5475 6375);
FORCEADD VCC_CORE..1
(5425 3575);
FORCEPROP 3 LASTPIN (5425 3525) SIG_NAME SW_P12V_STBY_PVDDIO_P0_FLT\g
J 0
(5435 3535);
DISPLAY 0.659574 (5435 3535);
PAINT MONO (5435 3535);
DISPLAY INVISIBLE (5435 3535);
FORCEPROP 1 LAST HDL_POWER SW_P12V_STBY_PVDDIO_P0_FLT
J 1
(5425 3625);
DISPLAY 0.489362 (5425 3625);
PAINT GREEN (5425 3625);
FORCEPROP 2 LAST CDS_LIB pure_quanta_power
J 0
(5425 3575);
DISPLAY INVISIBLE (5425 3575);
FORCEPROP 1 LAST PATH I101
J 0
(5475 3600);
DISPLAY 0.872340 (5475 3600);
PAINT AQUA (5475 3600);
DISPLAY INVISIBLE (5475 3600);
FORCEADD Q_CAP..1
(225 4700);
FORCEPROP 1 LAST LOCATION PC145_7
J 0
(275 4800);
DISPLAY 0.489362 (275 4800);
PAINT SKYBLUE (275 4800);
FORCEPROP 0 LAST $SEC 1
J 0
(275 4825);
DISPLAY 0.680851 (275 4825);
PAINT MONO (275 4825);
DISPLAY INVISIBLE (275 4825);
FORCEPROP 0 LAST CDS_SEC 1
J 0
(475 4750);
DISPLAY 1.021277 (475 4750);
DISPLAY INVISIBLE (475 4750);
FORCEPROP 1 LASTPIN (225 4800) $PN 1
J 0
(235 4780);
DISPLAY 0.489362 (235 4780);
PAINT MONO (235 4780);
FORCEPROP 1 LASTPIN (225 4600) $PN 2
J 0
(235 4580);
DISPLAY 0.489362 (235 4580);
PAINT MONO (235 4580);
FORCEPROP 1 LAST MATERIAL X7R
J 0
(275 4600);
DISPLAY 0.489362 (275 4600);
PAINT SKYBLUE (275 4600);
FORCEPROP 1 LAST TOLERANCE 10%
J 0
(275 4650);
DISPLAY 0.489362 (275 4650);
PAINT SKYBLUE (275 4650);
FORCEPROP 1 LAST VALUE 0.1UF
J 0
(275 4750);
DISPLAY 0.489362 (275 4750);
PAINT SKYBLUE (275 4750);
FORCEPROP 1 LAST PART_NUMBER CH4104K1B00
J 0
(275 4550);
DISPLAY 0.489362 (275 4550);
PAINT SKYBLUE (275 4550);
FORCEPROP 1 LAST VOLTAGE 25V
J 0
(275 4700);
DISPLAY 0.489362 (275 4700);
PAINT SKYBLUE (275 4700);
FORCEPROP 1 LAST PACK_TYPE 0402
J 0
(275 4500);
DISPLAY 0.489362 (275 4500);
PAINT SKYBLUE (275 4500);
FORCEPROP 2 LAST CDS_LIB pure_quanta
J 0
(225 4700);
DISPLAY INVISIBLE (225 4700);
FORCEPROP 1 LAST PATH I105
J 0
(275 4850);
DISPLAY 0.978723 (275 4850);
PAINT WHITE (275 4850);
DISPLAY INVISIBLE (275 4850);
FORCEADD Q_CAP..1
(250 1900);
FORCEPROP 1 LAST LOCATION PC146_8
J 0
(300 2000);
DISPLAY 0.489362 (300 2000);
PAINT SKYBLUE (300 2000);
FORCEPROP 0 LAST $SEC 1
J 0
(300 2025);
DISPLAY 0.680851 (300 2025);
PAINT MONO (300 2025);
DISPLAY INVISIBLE (300 2025);
FORCEPROP 0 LAST CDS_SEC 1
J 0
(500 1950);
DISPLAY 1.021277 (500 1950);
DISPLAY INVISIBLE (500 1950);
FORCEPROP 1 LASTPIN (250 2000) $PN 1
J 0
(260 1980);
DISPLAY 0.489362 (260 1980);
PAINT MONO (260 1980);
FORCEPROP 1 LASTPIN (250 1800) $PN 2
J 0
(260 1780);
DISPLAY 0.489362 (260 1780);
PAINT MONO (260 1780);
FORCEPROP 1 LAST MATERIAL X7R
J 0
(300 1800);
DISPLAY 0.489362 (300 1800);
PAINT SKYBLUE (300 1800);
FORCEPROP 1 LAST TOLERANCE 10%
J 0
(300 1850);
DISPLAY 0.489362 (300 1850);
PAINT SKYBLUE (300 1850);
FORCEPROP 1 LAST VALUE 0.1UF
J 0
(300 1950);
DISPLAY 0.489362 (300 1950);
PAINT SKYBLUE (300 1950);
FORCEPROP 1 LAST PART_NUMBER CH4104K1B00
J 0
(300 1750);
DISPLAY 0.489362 (300 1750);
PAINT SKYBLUE (300 1750);
FORCEPROP 1 LAST VOLTAGE 25V
J 0
(300 1900);
DISPLAY 0.489362 (300 1900);
PAINT SKYBLUE (300 1900);
FORCEPROP 1 LAST PACK_TYPE 0402
J 0
(300 1700);
DISPLAY 0.489362 (300 1700);
PAINT SKYBLUE (300 1700);
FORCEPROP 2 LAST CDS_LIB pure_quanta
J 0
(250 1900);
DISPLAY INVISIBLE (250 1900);
FORCEPROP 1 LAST PATH I106
J 0
(300 2050);
DISPLAY 0.978723 (300 2050);
PAINT WHITE (300 2050);
DISPLAY INVISIBLE (300 2050);
FORCEADD Q_RES..1
(5425 1250);
FORCEPROP 1 LAST LOCATION PR104
J 0
(5400 1300);
DISPLAY 0.489362 (5400 1300);
PAINT SKYBLUE (5400 1300);
FORCEPROP 0 LAST $SEC 1
J 0
(5675 1375);
DISPLAY 0.680851 (5675 1375);
PAINT MONO (5675 1375);
DISPLAY INVISIBLE (5675 1375);
FORCEPROP 0 LAST CDS_SEC 1
J 0
(5675 1375);
DISPLAY 1.021277 (5675 1375);
DISPLAY INVISIBLE (5675 1375);
FORCEPROP 1 LASTPIN (5325 1250) $PN 1
J 0
(5337 1262);
DISPLAY 0.787234 (5337 1262);
PAINT MONO (5337 1262);
DISPLAY INVISIBLE (5337 1262);
FORCEPROP 1 LASTPIN (5525 1250) $PN 2
J 0
(5487 1262);
DISPLAY 0.787234 (5487 1262);
PAINT MONO (5487 1262);
DISPLAY INVISIBLE (5487 1262);
FORCEPROP 1 LAST WATTAGE 1/16W
J 2
(5675 1325);
DISPLAY 0.489362 (5675 1325);
PAINT SKYBLUE (5675 1325);
FORCEPROP 1 LAST MATERIAL CHIP
J 0
(5575 1275);
DISPLAY 0.489362 (5575 1275);
PAINT SKYBLUE (5575 1275);
FORCEPROP 1 LAST TOLERANCE 5%
J 0
(5250 1300);
DISPLAY 0.489362 (5250 1300);
PAINT SKYBLUE (5250 1300);
FORCEPROP 1 LAST VALUE 0
J 2
(5225 1300);
DISPLAY 0.489362 (5225 1300);
PAINT SKYBLUE (5225 1300);
FORCEPROP 1 LAST PART_NUMBER CS00002JB38
J 0
(5150 1200);
DISPLAY 0.489362 (5150 1200);
PAINT SKYBLUE (5150 1200);
FORCEPROP 1 LAST PACK_TYPE 0402LF
J 0
(5500 1200);
DISPLAY 0.489362 (5500 1200);
PAINT SKYBLUE (5500 1200);
FORCEPROP 2 LAST CDS_LIB pure_quanta
J 0
(5425 1250);
DISPLAY INVISIBLE (5425 1250);
FORCEPROP 1 LAST PATH I107
J 0
(5375 1400);
DISPLAY 0.978723 (5375 1400);
PAINT WHITE (5375 1400);
DISPLAY INVISIBLE (5375 1400);
FORCEADD Q_RES..1
(5425 3975);
FORCEPROP 1 LAST LOCATION PR103
J 0
(5400 4000);
DISPLAY 0.489362 (5400 4000);
PAINT SKYBLUE (5400 4000);
FORCEPROP 0 LAST $SEC 1
J 0
(5675 4100);
DISPLAY 0.680851 (5675 4100);
PAINT MONO (5675 4100);
DISPLAY INVISIBLE (5675 4100);
FORCEPROP 0 LAST CDS_SEC 1
J 0
(5675 4100);
DISPLAY 1.021277 (5675 4100);
DISPLAY INVISIBLE (5675 4100);
FORCEPROP 1 LASTPIN (5325 3975) $PN 1
J 0
(5337 3987);
DISPLAY 0.787234 (5337 3987);
PAINT MONO (5337 3987);
DISPLAY INVISIBLE (5337 3987);
FORCEPROP 1 LASTPIN (5525 3975) $PN 2
J 0
(5487 3987);
DISPLAY 0.787234 (5487 3987);
PAINT MONO (5487 3987);
DISPLAY INVISIBLE (5487 3987);
FORCEPROP 1 LAST PACK_TYPE 0402LF
J 0
(5525 3925);
DISPLAY 0.489362 (5525 3925);
PAINT SKYBLUE (5525 3925);
FORCEPROP 1 LAST MATERIAL CHIP
J 0
(5575 4000);
DISPLAY 0.489362 (5575 4000);
PAINT SKYBLUE (5575 4000);
FORCEPROP 1 LAST WATTAGE 1/16W
J 2
(5675 4050);
DISPLAY 0.489362 (5675 4050);
PAINT SKYBLUE (5675 4050);
FORCEPROP 1 LAST TOLERANCE 5%
J 0
(5250 4025);
DISPLAY 0.489362 (5250 4025);
PAINT SKYBLUE (5250 4025);
FORCEPROP 1 LAST VALUE 0
J 2
(5225 4025);
DISPLAY 0.489362 (5225 4025);
PAINT SKYBLUE (5225 4025);
FORCEPROP 1 LAST PART_NUMBER CS00002JB38
J 0
(5125 3925);
DISPLAY 0.489362 (5125 3925);
PAINT SKYBLUE (5125 3925);
FORCEPROP 2 LAST CDS_LIB pure_quanta
J 0
(5425 3975);
DISPLAY INVISIBLE (5425 3975);
FORCEPROP 1 LAST PATH I108
J 0
(5375 4125);
DISPLAY 0.978723 (5375 4125);
PAINT WHITE (5375 4125);
DISPLAY INVISIBLE (5375 4125);
FORCEADD Q_CAP..1
(4825 5300);
FORCEPROP 1 LAST LOCATION PC155
J 0
(4875 5400);
DISPLAY 0.489362 (4875 5400);
PAINT SKYBLUE (4875 5400);
FORCEPROP 0 LAST $SEC 1
J 0
(4875 5450);
DISPLAY 0.680851 (4875 5450);
PAINT MONO (4875 5450);
DISPLAY INVISIBLE (4875 5450);
FORCEPROP 0 LAST CDS_SEC 1
J 2
(4875 5425);
DISPLAY 1.021277 (4875 5425);
DISPLAY INVISIBLE (4875 5425);
FORCEPROP 1 LASTPIN (4825 5400) $PN 1
J 0
(4835 5380);
DISPLAY 0.489362 (4835 5380);
PAINT MONO (4835 5380);
FORCEPROP 1 LASTPIN (4825 5200) $PN 2
J 0
(4835 5180);
DISPLAY 0.489362 (4835 5180);
PAINT MONO (4835 5180);
FORCEPROP 1 LAST PART_NUMBER CH4223K1B00
J 0
(4875 5150);
DISPLAY 0.489362 (4875 5150);
PAINT SKYBLUE (4875 5150);
FORCEPROP 1 LAST MATERIAL X7R
J 0
(4875 5200);
DISPLAY 0.489362 (4875 5200);
PAINT SKYBLUE (4875 5200);
FORCEPROP 1 LAST TOLERANCE 10%
J 0
(4875 5250);
DISPLAY 0.489362 (4875 5250);
PAINT SKYBLUE (4875 5250);
FORCEPROP 1 LAST VALUE 0.22UF
J 0
(4875 5350);
DISPLAY 0.489362 (4875 5350);
PAINT SKYBLUE (4875 5350);
FORCEPROP 1 LAST VOLTAGE 16V
J 0
(4875 5300);
DISPLAY 0.489362 (4875 5300);
PAINT SKYBLUE (4875 5300);
FORCEPROP 1 LAST PACK_TYPE 0402
J 0
(4875 5100);
DISPLAY 0.489362 (4875 5100);
PAINT SKYBLUE (4875 5100);
FORCEPROP 2 LAST CDS_LIB pure_quanta
J 2
(4825 5300);
DISPLAY INVISIBLE (4825 5300);
FORCEPROP 1 LAST PATH I109
J 0
(4875 5450);
DISPLAY 0.978723 (4875 5450);
PAINT WHITE (4875 5450);
DISPLAY INVISIBLE (4875 5450);
FORCEADD Q_CAP..1
(4825 2500);
FORCEPROP 1 LAST LOCATION PC156
J 0
(4875 2600);
DISPLAY 0.489362 (4875 2600);
PAINT SKYBLUE (4875 2600);
FORCEPROP 0 LAST $SEC 1
J 0
(4875 2650);
DISPLAY 0.680851 (4875 2650);
PAINT MONO (4875 2650);
DISPLAY INVISIBLE (4875 2650);
FORCEPROP 0 LAST CDS_SEC 1
J 2
(4875 2625);
DISPLAY 1.021277 (4875 2625);
DISPLAY INVISIBLE (4875 2625);
FORCEPROP 1 LASTPIN (4825 2600) $PN 1
J 0
(4835 2580);
DISPLAY 0.489362 (4835 2580);
PAINT MONO (4835 2580);
FORCEPROP 1 LASTPIN (4825 2400) $PN 2
J 0
(4835 2380);
DISPLAY 0.489362 (4835 2380);
PAINT MONO (4835 2380);
FORCEPROP 1 LAST PACK_TYPE 0402
J 0
(4875 2300);
DISPLAY 0.489362 (4875 2300);
PAINT SKYBLUE (4875 2300);
FORCEPROP 1 LAST MATERIAL X7R
J 0
(4875 2400);
DISPLAY 0.489362 (4875 2400);
PAINT SKYBLUE (4875 2400);
FORCEPROP 1 LAST PART_NUMBER CH4223K1B00
J 0
(4875 2350);
DISPLAY 0.489362 (4875 2350);
PAINT SKYBLUE (4875 2350);
FORCEPROP 1 LAST TOLERANCE 10%
J 0
(4875 2450);
DISPLAY 0.489362 (4875 2450);
PAINT SKYBLUE (4875 2450);
FORCEPROP 1 LAST VALUE 0.22UF
J 0
(4875 2550);
DISPLAY 0.489362 (4875 2550);
PAINT SKYBLUE (4875 2550);
FORCEPROP 1 LAST VOLTAGE 16V
J 0
(4875 2500);
DISPLAY 0.489362 (4875 2500);
PAINT SKYBLUE (4875 2500);
FORCEPROP 2 LAST CDS_LIB pure_quanta
J 2
(4825 2500);
DISPLAY INVISIBLE (4825 2500);
FORCEPROP 1 LAST PATH I110
J 0
(4875 2650);
DISPLAY 0.978723 (4875 2650);
PAINT WHITE (4875 2650);
DISPLAY INVISIBLE (4875 2650);
FORCEADD Q_INDUCTOR4P_14..1
(6200 2150);
FORCEPROP 1 LAST LOCATION PL18
J 0
(5875 2325);
DISPLAY 0.489362 (5875 2325);
PAINT SKYBLUE (5875 2325);
FORCEPROP 0 LAST $SEC 1
J 0
(6250 2350);
DISPLAY 0.680851 (6250 2350);
PAINT MONO (6250 2350);
DISPLAY INVISIBLE (6250 2350);
FORCEPROP 0 LAST CDS_SEC 1
J 0
(6250 2350);
DISPLAY 1.021277 (6250 2350);
DISPLAY INVISIBLE (6250 2350);
FORCEPROP 0 LASTPIN (5800 2275) $PN 1
J 2
(5790 2285);
DISPLAY 0.489362 (5790 2285);
PAINT MONO (5790 2285);
FORCEPROP 0 LASTPIN (5800 2025) $PN 2
J 2
(5790 2035);
DISPLAY 0.489362 (5790 2035);
PAINT MONO (5790 2035);
FORCEPROP 0 LASTPIN (6600 2025) $PN 3
J 0
(6610 2035);
DISPLAY 0.489362 (6610 2035);
PAINT MONO (6610 2035);
FORCEPROP 0 LASTPIN (6600 2275) $PN 4
J 0
(6610 2285);
DISPLAY 0.489362 (6610 2285);
PAINT MONO (6610 2285);
FORCEPROP 2 LAST PART_TYPE SMLF
J 0
(6125 1900);
DISPLAY 1.021277 (6125 1900);
FORCEPROP 1 LAST PART_NUMBER CV+15^0TZ04
J 0
(6250 2325);
DISPLAY 0.489362 (6250 2325);
PAINT SKYBLUE (6250 2325);
FORCEPROP 1 LAST MATERIAL IND
J 0
(6000 2325);
DISPLAY 0.489362 (6000 2325);
PAINT SKYBLUE (6000 2325);
FORCEPROP 2 LAST VALUE 150NH
J 0
(6100 2325);
DISPLAY 0.489362 (6100 2325);
PAINT SKYBLUE (6100 2325);
FORCEPROP 2 LAST CDS_LIB pure_quanta
J 0
(6200 2150);
DISPLAY INVISIBLE (6200 2150);
FORCEPROP 1 LAST NEEDS_NO_SIZE TRUE
J 0
(6200 2150);
DISPLAY 0.468085 (6200 2150);
PAINT GREEN (6200 2150);
DISPLAY INVISIBLE (6200 2150);
FORCEPROP 1 LAST PATH I111
J 0
(6400 2305);
DISPLAY 0.723404 (6400 2305);
PAINT GREEN (6400 2305);
DISPLAY INVISIBLE (6400 2305);
FORCEADD Q_INDUCTOR4P_14..1
(6025 4950);
FORCEPROP 1 LAST LOCATION PL17
J 0
(5750 5125);
DISPLAY 0.489362 (5750 5125);
PAINT SKYBLUE (5750 5125);
FORCEPROP 0 LAST $SEC 1
J 0
(6075 5150);
DISPLAY 0.680851 (6075 5150);
PAINT MONO (6075 5150);
DISPLAY INVISIBLE (6075 5150);
FORCEPROP 0 LAST CDS_SEC 1
J 0
(6075 5150);
DISPLAY 1.021277 (6075 5150);
DISPLAY INVISIBLE (6075 5150);
FORCEPROP 0 LASTPIN (5625 5075) $PN 1
J 2
(5615 5085);
DISPLAY 0.489362 (5615 5085);
PAINT MONO (5615 5085);
FORCEPROP 0 LASTPIN (5625 4825) $PN 2
J 2
(5615 4835);
DISPLAY 0.489362 (5615 4835);
PAINT MONO (5615 4835);
FORCEPROP 0 LASTPIN (6425 4825) $PN 3
J 0
(6435 4835);
DISPLAY 0.489362 (6435 4835);
PAINT MONO (6435 4835);
FORCEPROP 0 LASTPIN (6425 5075) $PN 4
J 0
(6435 5085);
DISPLAY 0.489362 (6435 5085);
PAINT MONO (6435 5085);
FORCEPROP 2 LAST PART_TYPE SMLF
J 0
(5950 4700);
DISPLAY 1.021277 (5950 4700);
FORCEPROP 1 LAST MATERIAL IND
J 0
(5825 5125);
DISPLAY 0.489362 (5825 5125);
PAINT SKYBLUE (5825 5125);
FORCEPROP 2 LAST VALUE 150NH
J 0
(5925 5125);
DISPLAY 0.489362 (5925 5125);
PAINT SKYBLUE (5925 5125);
FORCEPROP 1 LAST PART_NUMBER CV+15^0TZ04
J 0
(6075 5125);
DISPLAY 0.489362 (6075 5125);
PAINT SKYBLUE (6075 5125);
FORCEPROP 1 LAST NEEDS_NO_SIZE TRUE
J 0
(6025 4950);
DISPLAY 0.468085 (6025 4950);
PAINT GREEN (6025 4950);
DISPLAY INVISIBLE (6025 4950);
FORCEPROP 2 LAST CDS_LIB pure_quanta
J 0
(6025 4950);
DISPLAY INVISIBLE (6025 4950);
FORCEPROP 1 LAST PATH I112
J 0
(6225 5105);
DISPLAY 0.723404 (6225 5105);
PAINT GREEN (6225 5105);
DISPLAY INVISIBLE (6225 5105);
FORCEADD Q_RES..1
(4100 2625);
FORCEPROP 1 LAST LOCATION PR102
J 0
(3850 2675);
DISPLAY 0.489362 (3850 2675);
PAINT SKYBLUE (3850 2675);
FORCEPROP 0 LAST $SEC 1
J 0
(4275 2700);
DISPLAY 0.680851 (4275 2700);
PAINT MONO (4275 2700);
DISPLAY INVISIBLE (4275 2700);
FORCEPROP 0 LAST CDS_SEC 1
J 0
(4275 2700);
DISPLAY 1.021277 (4275 2700);
DISPLAY INVISIBLE (4275 2700);
FORCEPROP 1 LASTPIN (4000 2625) $PN 1
J 0
(4012 2637);
DISPLAY 0.787234 (4012 2637);
PAINT MONO (4012 2637);
DISPLAY INVISIBLE (4012 2637);
FORCEPROP 1 LASTPIN (4200 2625) $PN 2
J 0
(4162 2637);
DISPLAY 0.787234 (4162 2637);
PAINT MONO (4162 2637);
DISPLAY INVISIBLE (4162 2637);
FORCEPROP 1 LAST PACK_TYPE 0402LF
J 0
(4500 2550);
DISPLAY 0.489362 (4500 2550);
PAINT SKYBLUE (4500 2550);
FORCEPROP 1 LAST TOLERANCE 1%
J 0
(4075 2675);
DISPLAY 0.489362 (4075 2675);
PAINT SKYBLUE (4075 2675);
FORCEPROP 1 LAST MATERIAL CHIP
J 0
(3950 2550);
DISPLAY 0.489362 (3950 2550);
PAINT SKYBLUE (3950 2550);
FORCEPROP 1 LAST WATTAGE 1/16W
J 2
(4275 2675);
DISPLAY 0.489362 (4275 2675);
PAINT SKYBLUE (4275 2675);
FORCEPROP 1 LAST VALUE 4.7
J 2
(4050 2675);
DISPLAY 0.489362 (4050 2675);
PAINT SKYBLUE (4050 2675);
FORCEPROP 1 LAST PART_NUMBER CS-4702FB19
J 0
(4125 2550);
DISPLAY 0.489362 (4125 2550);
PAINT SKYBLUE (4125 2550);
FORCEPROP 1 LAST PATH I113
J 0
(4050 2775);
DISPLAY 0.978723 (4050 2775);
PAINT WHITE (4050 2775);
DISPLAY INVISIBLE (4050 2775);
FORCEPROP 2 LAST CDS_LIB pure_quanta
J 0
(4100 2625);
DISPLAY INVISIBLE (4100 2625);
FORCEADD Q_CAPP..1
(5625 6000);
FORCEPROP 1 LAST LOCATION PC164
J 0
(5675 6125);
DISPLAY 0.489362 (5675 6125);
PAINT SKYBLUE (5675 6125);
FORCEPROP 0 LAST $SEC 1
J 0
(5675 6125);
DISPLAY 0.680851 (5675 6125);
PAINT MONO (5675 6125);
DISPLAY INVISIBLE (5675 6125);
FORCEPROP 0 LAST CDS_SEC 1
J 0
(5675 6125);
DISPLAY 1.021277 (5675 6125);
DISPLAY INVISIBLE (5675 6125);
FORCEPROP 1 LASTPIN (5625 6100) $PN 1
J 0
(5635 6085);
DISPLAY 0.489362 (5635 6085);
PAINT MONO (5635 6085);
FORCEPROP 1 LASTPIN (5625 5900) $PN 2
J 0
(5635 5885);
DISPLAY 0.489362 (5635 5885);
PAINT MONO (5635 5885);
FORCEPROP 1 LAST TOLERANCE 20%
J 0
(5675 6025);
DISPLAY 0.489362 (5675 6025);
PAINT SKYBLUE (5675 6025);
FORCEPROP 1 LAST VALUE 220UF
J 0
(5675 6075);
DISPLAY 0.489362 (5675 6075);
PAINT SKYBLUE (5675 6075);
FORCEPROP 1 LAST MATERIAL OSCON
J 0
(5675 5925);
DISPLAY 0.489362 (5675 5925);
PAINT SKYBLUE (5675 5925);
FORCEPROP 1 LAST PART_NUMBER CC72204MD02
J 0
(5675 5825);
DISPLAY 0.489362 (5675 5825);
PAINT SKYBLUE (5675 5825);
FORCEPROP 1 LAST VOLTAGE 25V
J 0
(5675 5975);
DISPLAY 0.489362 (5675 5975);
PAINT SKYBLUE (5675 5975);
FORCEPROP 1 LAST PACK_TYPE THLF
J 0
(5675 5875);
DISPLAY 0.489362 (5675 5875);
PAINT SKYBLUE (5675 5875);
FORCEPROP 2 LAST CDS_LIB pure_quanta
J 0
(5625 6000);
DISPLAY INVISIBLE (5625 6000);
FORCEPROP 1 LAST PATH I115
J 0
(5675 6150);
DISPLAY 0.978723 (5675 6150);
DISPLAY INVISIBLE (5675 6150);
FORCEADD OFFPAGE..5
(1300 4575);
FORCEPROP 2 LAST $XR2 176 
J 0
(1045 4611);
DISPLAY 0.638298 (1045 4611);
PAINT MONO (1045 4611);
FORCEPROP 2 LAST $XR1 182 
J 0
(1045 4539);
DISPLAY 0.638298 (1045 4539);
PAINT MONO (1045 4539);
FORCEPROP 2 LAST $XR0 181 
J 0
(1045 4575);
DISPLAY 0.638298 (1045 4575);
PAINT MONO (1045 4575);
FORCEPROP 2 LAST CDS_LIB standard
J 0
(1300 4575);
DISPLAY INVISIBLE (1300 4575);
FORCEPROP 1 LAST OFFPAGE TRUE
J 0
(1625 4450);
DISPLAY 0.872340 (1625 4450);
PAINT GREEN (1625 4450);
DISPLAY INVISIBLE (1625 4450);
FORCEPROP 1 LAST COMMENT_BODY TRUE
J 0
(1400 4500);
DISPLAY 0.872340 (1400 4500);
PAINT GREEN (1400 4500);
DISPLAY INVISIBLE (1400 4500);
FORCEPROP 2 LAST PATH I116
J 0
(1350 4650);
DISPLAY 1.021277 (1350 4650);
DISPLAY INVISIBLE (1350 4650);
FORCEADD OFFPAGE..5
(1275 1775);
FORCEPROP 2 LAST $XR2 176 
J 0
(990 1811);
DISPLAY 0.638298 (990 1811);
PAINT MONO (990 1811);
FORCEPROP 2 LAST $XR1 182 
J 0
(990 1739);
DISPLAY 0.638298 (990 1739);
PAINT MONO (990 1739);
FORCEPROP 2 LAST $XR0 181 
J 0
(990 1775);
DISPLAY 0.638298 (990 1775);
PAINT MONO (990 1775);
FORCEPROP 2 LAST CDS_LIB standard
J 0
(1275 1775);
DISPLAY INVISIBLE (1275 1775);
FORCEPROP 1 LAST OFFPAGE TRUE
J 0
(1600 1650);
DISPLAY 0.872340 (1600 1650);
PAINT GREEN (1600 1650);
DISPLAY INVISIBLE (1600 1650);
FORCEPROP 1 LAST COMMENT_BODY TRUE
J 0
(1375 1700);
DISPLAY 0.872340 (1375 1700);
PAINT GREEN (1375 1700);
DISPLAY INVISIBLE (1375 1700);
FORCEPROP 2 LAST PATH I117
J 0
(1325 1850);
DISPLAY 1.021277 (1325 1850);
DISPLAY INVISIBLE (1325 1850);
FORCEADD Q_CAPP..1
(7125 3275);
FORCEPROP 1 LAST LOCATION PC160
J 0
(7175 3425);
DISPLAY 0.489362 (7175 3425);
PAINT SKYBLUE (7175 3425);
FORCEPROP 0 LAST $SEC 1
J 0
(7175 3450);
DISPLAY 0.680851 (7175 3450);
PAINT MONO (7175 3450);
DISPLAY INVISIBLE (7175 3450);
FORCEPROP 0 LAST CDS_SEC 1
J 0
(7175 3450);
DISPLAY 1.021277 (7175 3450);
DISPLAY INVISIBLE (7175 3450);
FORCEPROP 1 LASTPIN (7125 3375) $PN 1
J 0
(7135 3360);
DISPLAY 0.489362 (7135 3360);
PAINT MONO (7135 3360);
FORCEPROP 1 LASTPIN (7125 3175) $PN 2
J 0
(7135 3160);
DISPLAY 0.489362 (7135 3160);
PAINT MONO (7135 3160);
FORCEPROP 1 LAST PACK_TYPE SMLF
J 0
(7175 3175);
DISPLAY 0.489362 (7175 3175);
PAINT SKYBLUE (7175 3175);
FORCEPROP 1 LAST PART_NUMBER CH747LM8825
J 0
(7175 3125);
DISPLAY 0.489362 (7175 3125);
PAINT SKYBLUE (7175 3125);
FORCEPROP 1 LAST MATERIAL EMPTY
J 0
(7175 3225);
DISPLAY 0.489362 (7175 3225);
PAINT RED (7175 3225);
FORCEPROP 1 LAST TOLERANCE 20%
J 0
(7175 3325);
DISPLAY 0.489362 (7175 3325);
PAINT SKYBLUE (7175 3325);
FORCEPROP 1 LAST VALUE 470UF
J 0
(7175 3375);
DISPLAY 0.489362 (7175 3375);
PAINT SKYBLUE (7175 3375);
FORCEPROP 1 LAST VOLTAGE 2.5V
J 0
(7175 3275);
DISPLAY 0.489362 (7175 3275);
PAINT SKYBLUE (7175 3275);
FORCEPROP 2 LAST CDS_LIB pure_quanta
J 0
(7125 3275);
DISPLAY INVISIBLE (7125 3275);
FORCEPROP 1 LAST PATH I118
J 0
(7175 3425);
DISPLAY 0.978723 (7175 3425);
DISPLAY INVISIBLE (7175 3425);
FORCEADD Q_CAP..1
(3575 5975);
FORCEPROP 1 LAST LOCATION PC148_1
J 0
(3650 6125);
DISPLAY 0.489362 (3650 6125);
PAINT SKYBLUE (3650 6125);
FORCEPROP 0 LAST $SEC 1
J 0
(3625 6125);
DISPLAY 0.680851 (3625 6125);
PAINT MONO (3625 6125);
DISPLAY INVISIBLE (3625 6125);
FORCEPROP 0 LAST CDS_SEC 1
J 0
(3625 6125);
DISPLAY 1.021277 (3625 6125);
DISPLAY INVISIBLE (3625 6125);
FORCEPROP 1 LASTPIN (3575 6075) $PN 1
J 0
(3585 6055);
DISPLAY 0.489362 (3585 6055);
PAINT MONO (3585 6055);
FORCEPROP 1 LASTPIN (3575 5875) $PN 2
J 0
(3585 5855);
DISPLAY 0.489362 (3585 5855);
PAINT MONO (3585 5855);
FORCEPROP 1 LAST MATERIAL X7R
J 0
(3650 5925);
DISPLAY 0.489362 (3650 5925);
PAINT SKYBLUE (3650 5925);
FORCEPROP 1 LAST TOLERANCE 10%
J 0
(3650 5975);
DISPLAY 0.489362 (3650 5975);
PAINT SKYBLUE (3650 5975);
FORCEPROP 1 LAST VALUE 0.1UF
J 0
(3650 6075);
DISPLAY 0.489362 (3650 6075);
PAINT SKYBLUE (3650 6075);
FORCEPROP 1 LAST PART_NUMBER CH4104K1B00
J 0
(3650 5875);
DISPLAY 0.489362 (3650 5875);
PAINT SKYBLUE (3650 5875);
FORCEPROP 1 LAST VOLTAGE 25V
J 0
(3650 6025);
DISPLAY 0.489362 (3650 6025);
PAINT SKYBLUE (3650 6025);
FORCEPROP 1 LAST PACK_TYPE 0402
J 0
(3650 5825);
DISPLAY 0.489362 (3650 5825);
PAINT SKYBLUE (3650 5825);
FORCEPROP 2 LAST CDS_LIB pure_quanta
J 0
(3575 5975);
DISPLAY INVISIBLE (3575 5975);
FORCEPROP 1 LAST PATH I119
J 0
(3625 6125);
DISPLAY 0.978723 (3625 6125);
PAINT WHITE (3625 6125);
DISPLAY INVISIBLE (3625 6125);
FORCEADD Q_CAP..1
(3650 3200);
FORCEPROP 1 LAST LOCATION PC149_2
J 0
(3700 3350);
DISPLAY 0.489362 (3700 3350);
PAINT SKYBLUE (3700 3350);
FORCEPROP 0 LAST $SEC 1
J 0
(3700 3350);
DISPLAY 0.680851 (3700 3350);
PAINT MONO (3700 3350);
DISPLAY INVISIBLE (3700 3350);
FORCEPROP 0 LAST CDS_SEC 1
J 0
(3700 3350);
DISPLAY 1.021277 (3700 3350);
DISPLAY INVISIBLE (3700 3350);
FORCEPROP 1 LASTPIN (3650 3300) $PN 1
J 0
(3660 3280);
DISPLAY 0.489362 (3660 3280);
PAINT MONO (3660 3280);
FORCEPROP 1 LASTPIN (3650 3100) $PN 2
J 0
(3660 3080);
DISPLAY 0.489362 (3660 3080);
PAINT MONO (3660 3080);
FORCEPROP 1 LAST MATERIAL X7R
J 0
(3700 3150);
DISPLAY 0.489362 (3700 3150);
PAINT SKYBLUE (3700 3150);
FORCEPROP 1 LAST TOLERANCE 10%
J 0
(3700 3200);
DISPLAY 0.489362 (3700 3200);
PAINT SKYBLUE (3700 3200);
FORCEPROP 1 LAST VALUE 0.1UF
J 0
(3700 3300);
DISPLAY 0.489362 (3700 3300);
PAINT SKYBLUE (3700 3300);
FORCEPROP 1 LAST PART_NUMBER CH4104K1B00
J 0
(3700 3100);
DISPLAY 0.489362 (3700 3100);
PAINT SKYBLUE (3700 3100);
FORCEPROP 1 LAST VOLTAGE 25V
J 0
(3700 3250);
DISPLAY 0.489362 (3700 3250);
PAINT SKYBLUE (3700 3250);
FORCEPROP 1 LAST PACK_TYPE 0402
J 0
(3700 3050);
DISPLAY 0.489362 (3700 3050);
PAINT SKYBLUE (3700 3050);
FORCEPROP 2 LAST CDS_LIB pure_quanta
J 0
(3650 3200);
DISPLAY INVISIBLE (3650 3200);
FORCEPROP 1 LAST PATH I120
J 0
(3700 3350);
DISPLAY 0.978723 (3700 3350);
PAINT WHITE (3700 3350);
DISPLAY INVISIBLE (3700 3350);
FORCEADD Q_CAP..1
(1250 5350);
FORCEPROP 1 LAST LOCATION PC143
J 0
(1300 5450);
DISPLAY 0.489362 (1300 5450);
PAINT SKYBLUE (1300 5450);
FORCEPROP 0 LAST $SEC 1
J 0
(1300 5500);
DISPLAY 0.680851 (1300 5500);
PAINT MONO (1300 5500);
DISPLAY INVISIBLE (1300 5500);
FORCEPROP 0 LAST CDS_SEC 1
J 0
(1300 5500);
DISPLAY 1.021277 (1300 5500);
DISPLAY INVISIBLE (1300 5500);
FORCEPROP 1 LASTPIN (1250 5450) $PN 1
J 0
(1260 5430);
DISPLAY 0.489362 (1260 5430);
PAINT MONO (1260 5430);
FORCEPROP 1 LASTPIN (1250 5250) $PN 2
J 0
(1260 5230);
DISPLAY 0.489362 (1260 5230);
PAINT MONO (1260 5230);
FORCEPROP 1 LAST MATERIAL X6S
J 0
(1300 5250);
DISPLAY 0.489362 (1300 5250);
PAINT SKYBLUE (1300 5250);
FORCEPROP 1 LAST TOLERANCE 10%
J 0
(1300 5300);
DISPLAY 0.489362 (1300 5300);
PAINT SKYBLUE (1300 5300);
FORCEPROP 1 LAST VALUE 2.2UF
J 0
(1300 5400);
DISPLAY 0.489362 (1300 5400);
PAINT SKYBLUE (1300 5400);
FORCEPROP 1 LAST PART_NUMBER CH5222KEB01
J 0
(1300 5200);
DISPLAY 0.489362 (1300 5200);
PAINT SKYBLUE (1300 5200);
FORCEPROP 1 LAST VOLTAGE 10V
J 0
(1300 5350);
DISPLAY 0.489362 (1300 5350);
PAINT SKYBLUE (1300 5350);
FORCEPROP 1 LAST PACK_TYPE C0402
J 0
(1300 5150);
DISPLAY 0.489362 (1300 5150);
PAINT SKYBLUE (1300 5150);
FORCEPROP 2 LAST CDS_LIB pure_quanta
J 0
(1250 5350);
DISPLAY INVISIBLE (1250 5350);
FORCEPROP 1 LAST PATH I121
J 0
(1300 5500);
DISPLAY 0.978723 (1300 5500);
PAINT WHITE (1300 5500);
DISPLAY INVISIBLE (1300 5500);
FORCEADD UNIVERSAL_GND..1
(1250 5150);
FORCEPROP 3 LASTPIN (1250 5200) SIG_NAME GND\g
J 0
(1260 5210);
DISPLAY 0.659574 (1260 5210);
PAINT MONO (1260 5210);
DISPLAY INVISIBLE (1260 5210);
FORCEPROP 2 LAST CDS_LIB pure_quanta_power
J 0
(1250 5150);
DISPLAY INVISIBLE (1250 5150);
FORCEPROP 1 LAST PATH I122
J 0
(1325 5150);
DISPLAY 0.872340 (1325 5150);
PAINT AQUA (1325 5150);
DISPLAY INVISIBLE (1325 5150);
FORCEPROP 1 LAST HDL_POWER GND
J 1
(1275 5075);
DISPLAY 0.872340 (1275 5075);
PAINT GREEN (1275 5075);
DISPLAY INVISIBLE (1275 5075);
FORCEADD UNIVERSAL_GND..1
(1600 5650);
FORCEPROP 3 LASTPIN (1600 5700) SIG_NAME GND\g
J 0
(1610 5710);
DISPLAY 0.659574 (1610 5710);
PAINT MONO (1610 5710);
DISPLAY INVISIBLE (1610 5710);
FORCEPROP 2 LAST CDS_LIB pure_quanta_power
J 0
(1600 5650);
DISPLAY INVISIBLE (1600 5650);
FORCEPROP 1 LAST PATH I123
J 0
(1675 5650);
DISPLAY 0.872340 (1675 5650);
PAINT AQUA (1675 5650);
DISPLAY INVISIBLE (1675 5650);
FORCEPROP 1 LAST HDL_POWER GND
J 1
(1625 5575);
DISPLAY 0.872340 (1625 5575);
PAINT GREEN (1625 5575);
DISPLAY INVISIBLE (1625 5575);
FORCEADD Q_RES..2
(1250 5900);
FORCEPROP 1 LAST LOCATION PR100
J 0
(1295 6025);
DISPLAY 0.489362 (1295 6025);
PAINT SKYBLUE (1295 6025);
FORCEPROP 0 LAST $SEC 1
J 0
(1300 6075);
DISPLAY 0.680851 (1300 6075);
PAINT MONO (1300 6075);
DISPLAY INVISIBLE (1300 6075);
FORCEPROP 0 LAST CDS_SEC 1
J 0
(1300 6075);
DISPLAY 1.021277 (1300 6075);
DISPLAY INVISIBLE (1300 6075);
FORCEPROP 1 LASTPIN (1250 6000) $PN 1
J 0
(1255 5962);
DISPLAY 0.489362 (1255 5962);
PAINT MONO (1255 5962);
FORCEPROP 1 LASTPIN (1250 5800) $PN 2
J 0
(1255 5810);
DISPLAY 0.489362 (1255 5810);
PAINT MONO (1255 5810);
FORCEPROP 1 LAST WATTAGE 1/16W
J 0
(1300 5875);
DISPLAY 0.489362 (1300 5875);
PAINT SKYBLUE (1300 5875);
FORCEPROP 1 LAST MATERIAL CHIP
J 0
(1300 5825);
DISPLAY 0.489362 (1300 5825);
PAINT SKYBLUE (1300 5825);
FORCEPROP 1 LAST TOLERANCE 1%
J 0
(1300 5925);
DISPLAY 0.489362 (1300 5925);
PAINT SKYBLUE (1300 5925);
FORCEPROP 1 LAST VALUE 2.2
J 0
(1300 5975);
DISPLAY 0.489362 (1300 5975);
PAINT SKYBLUE (1300 5975);
FORCEPROP 1 LAST PART_NUMBER CS-2202FB00
J 0
(1300 5775);
DISPLAY 0.489362 (1300 5775);
PAINT SKYBLUE (1300 5775);
FORCEPROP 1 LAST PACK_TYPE 0402LF
J 0
(1300 5725);
DISPLAY 0.489362 (1300 5725);
PAINT SKYBLUE (1300 5725);
FORCEPROP 2 LAST CDS_LIB pure_quanta
J 0
(1250 5900);
DISPLAY INVISIBLE (1250 5900);
FORCEPROP 1 LAST PATH I124
J 0
(1300 6075);
DISPLAY 0.978723 (1300 6075);
PAINT WHITE (1300 6075);
DISPLAY INVISIBLE (1300 6075);
FORCEADD Q_CAP..1
(1600 5925);
FORCEPROP 1 LAST LOCATION PC147_IOP0_1
J 0
(1650 6025);
DISPLAY 0.489362 (1650 6025);
PAINT SKYBLUE (1650 6025);
FORCEPROP 0 LAST $SEC 1
J 0
(1650 6075);
DISPLAY 0.680851 (1650 6075);
PAINT MONO (1650 6075);
DISPLAY INVISIBLE (1650 6075);
FORCEPROP 0 LAST CDS_SEC 1
J 0
(1650 6075);
DISPLAY 1.021277 (1650 6075);
DISPLAY INVISIBLE (1650 6075);
FORCEPROP 1 LASTPIN (1600 6025) $PN 1
J 0
(1610 6005);
DISPLAY 0.489362 (1610 6005);
PAINT MONO (1610 6005);
FORCEPROP 1 LASTPIN (1600 5825) $PN 2
J 0
(1610 5805);
DISPLAY 0.489362 (1610 5805);
PAINT MONO (1610 5805);
FORCEPROP 1 LAST MATERIAL X6S
J 0
(1650 5825);
DISPLAY 0.489362 (1650 5825);
PAINT SKYBLUE (1650 5825);
FORCEPROP 1 LAST VALUE 2.2UF
J 0
(1650 5975);
DISPLAY 0.489362 (1650 5975);
PAINT SKYBLUE (1650 5975);
FORCEPROP 1 LAST VOLTAGE 10V
J 0
(1650 5925);
DISPLAY 0.489362 (1650 5925);
PAINT SKYBLUE (1650 5925);
FORCEPROP 1 LAST PACK_TYPE C0402
J 0
(1650 5725);
DISPLAY 0.489362 (1650 5725);
PAINT SKYBLUE (1650 5725);
FORCEPROP 1 LAST TOLERANCE 10%
J 0
(1650 5875);
DISPLAY 0.489362 (1650 5875);
PAINT SKYBLUE (1650 5875);
FORCEPROP 1 LAST PART_NUMBER CH5222KEB01
J 0
(1650 5775);
DISPLAY 0.489362 (1650 5775);
PAINT SKYBLUE (1650 5775);
FORCEPROP 2 LAST CDS_LIB pure_quanta
J 0
(1600 5925);
DISPLAY INVISIBLE (1600 5925);
FORCEPROP 1 LAST PATH I125
J 0
(1650 6075);
DISPLAY 0.978723 (1650 6075);
PAINT WHITE (1650 6075);
DISPLAY INVISIBLE (1650 6075);
FORCEADD Q_CAP..1
(1150 2675);
FORCEPROP 1 LAST LOCATION PC142
J 0
(1200 2775);
DISPLAY 0.489362 (1200 2775);
PAINT SKYBLUE (1200 2775);
FORCEPROP 0 LAST $SEC 1
J 0
(1200 2825);
DISPLAY 0.680851 (1200 2825);
PAINT MONO (1200 2825);
DISPLAY INVISIBLE (1200 2825);
FORCEPROP 0 LAST CDS_SEC 1
J 0
(1200 2825);
DISPLAY 1.021277 (1200 2825);
DISPLAY INVISIBLE (1200 2825);
FORCEPROP 1 LASTPIN (1150 2775) $PN 1
J 0
(1160 2755);
DISPLAY 0.489362 (1160 2755);
PAINT MONO (1160 2755);
FORCEPROP 1 LASTPIN (1150 2575) $PN 2
J 0
(1160 2555);
DISPLAY 0.489362 (1160 2555);
PAINT MONO (1160 2555);
FORCEPROP 1 LAST MATERIAL X6S
J 0
(1200 2575);
DISPLAY 0.489362 (1200 2575);
PAINT SKYBLUE (1200 2575);
FORCEPROP 1 LAST TOLERANCE 10%
J 0
(1200 2625);
DISPLAY 0.489362 (1200 2625);
PAINT SKYBLUE (1200 2625);
FORCEPROP 1 LAST VALUE 2.2UF
J 0
(1200 2725);
DISPLAY 0.489362 (1200 2725);
PAINT SKYBLUE (1200 2725);
FORCEPROP 1 LAST PART_NUMBER CH5222KEB01
J 0
(1200 2525);
DISPLAY 0.489362 (1200 2525);
PAINT SKYBLUE (1200 2525);
FORCEPROP 1 LAST VOLTAGE 10V
J 0
(1200 2675);
DISPLAY 0.489362 (1200 2675);
PAINT SKYBLUE (1200 2675);
FORCEPROP 1 LAST PACK_TYPE C0402
J 0
(1200 2475);
DISPLAY 0.489362 (1200 2475);
PAINT SKYBLUE (1200 2475);
FORCEPROP 2 LAST CDS_LIB pure_quanta
J 0
(1150 2675);
DISPLAY INVISIBLE (1150 2675);
FORCEPROP 1 LAST PATH I127
J 0
(1200 2825);
DISPLAY 0.978723 (1200 2825);
PAINT WHITE (1200 2825);
DISPLAY INVISIBLE (1200 2825);
FORCEADD UNIVERSAL_GND..1
(1150 2475);
FORCEPROP 3 LASTPIN (1150 2525) SIG_NAME GND\g
J 0
(1160 2535);
DISPLAY 0.659574 (1160 2535);
PAINT MONO (1160 2535);
DISPLAY INVISIBLE (1160 2535);
FORCEPROP 2 LAST CDS_LIB pure_quanta_power
J 0
(1150 2475);
DISPLAY INVISIBLE (1150 2475);
FORCEPROP 1 LAST PATH I128
J 0
(1225 2475);
DISPLAY 0.872340 (1225 2475);
PAINT AQUA (1225 2475);
DISPLAY INVISIBLE (1225 2475);
FORCEPROP 1 LAST HDL_POWER GND
J 1
(1175 2400);
DISPLAY 0.872340 (1175 2400);
PAINT GREEN (1175 2400);
DISPLAY INVISIBLE (1175 2400);
FORCEADD UNIVERSAL_GND..1
(1500 2975);
FORCEPROP 3 LASTPIN (1500 3025) SIG_NAME GND\g
J 0
(1510 3035);
DISPLAY 0.659574 (1510 3035);
PAINT MONO (1510 3035);
DISPLAY INVISIBLE (1510 3035);
FORCEPROP 2 LAST CDS_LIB pure_quanta_power
J 0
(1500 2975);
DISPLAY INVISIBLE (1500 2975);
FORCEPROP 1 LAST PATH I129
J 0
(1575 2975);
DISPLAY 0.872340 (1575 2975);
PAINT AQUA (1575 2975);
DISPLAY INVISIBLE (1575 2975);
FORCEPROP 1 LAST HDL_POWER GND
J 1
(1525 2900);
DISPLAY 0.872340 (1525 2900);
PAINT GREEN (1525 2900);
DISPLAY INVISIBLE (1525 2900);
FORCEADD UNIVERSAL_GND..1
(850 4400);
FORCEPROP 3 LASTPIN (850 4450) SIG_NAME GND\g
J 0
(860 4460);
DISPLAY 0.659574 (860 4460);
PAINT MONO (860 4460);
DISPLAY INVISIBLE (860 4460);
FORCEPROP 2 LAST CDS_LIB pure_quanta_power
J 0
(850 4400);
PAINT MONO (850 4400);
DISPLAY INVISIBLE (850 4400);
FORCEPROP 1 LAST PATH I13
J 0
(925 4400);
DISPLAY 0.872340 (925 4400);
PAINT AQUA (925 4400);
DISPLAY INVISIBLE (925 4400);
FORCEPROP 1 LAST HDL_POWER GND
J 1
(875 4325);
DISPLAY 0.872340 (875 4325);
PAINT GREEN (875 4325);
DISPLAY INVISIBLE (875 4325);
FORCEADD Q_RES..2
(1150 3225);
FORCEPROP 1 LAST LOCATION PR99
J 0
(1195 3350);
DISPLAY 0.489362 (1195 3350);
PAINT SKYBLUE (1195 3350);
FORCEPROP 0 LAST $SEC 1
J 0
(1200 3400);
DISPLAY 0.680851 (1200 3400);
PAINT MONO (1200 3400);
DISPLAY INVISIBLE (1200 3400);
FORCEPROP 0 LAST CDS_SEC 1
J 0
(1200 3400);
DISPLAY 1.021277 (1200 3400);
DISPLAY INVISIBLE (1200 3400);
FORCEPROP 1 LASTPIN (1150 3325) $PN 1
J 0
(1155 3287);
DISPLAY 0.489362 (1155 3287);
PAINT MONO (1155 3287);
FORCEPROP 1 LASTPIN (1150 3125) $PN 2
J 0
(1155 3135);
DISPLAY 0.489362 (1155 3135);
PAINT MONO (1155 3135);
FORCEPROP 1 LAST WATTAGE 1/16W
J 0
(1200 3200);
DISPLAY 0.489362 (1200 3200);
PAINT SKYBLUE (1200 3200);
FORCEPROP 1 LAST MATERIAL CHIP
J 0
(1200 3150);
DISPLAY 0.489362 (1200 3150);
PAINT SKYBLUE (1200 3150);
FORCEPROP 1 LAST TOLERANCE 1%
J 0
(1200 3250);
DISPLAY 0.489362 (1200 3250);
PAINT SKYBLUE (1200 3250);
FORCEPROP 1 LAST VALUE 2.2
J 0
(1200 3300);
DISPLAY 0.489362 (1200 3300);
PAINT SKYBLUE (1200 3300);
FORCEPROP 1 LAST PART_NUMBER CS-2202FB00
J 0
(1200 3100);
DISPLAY 0.489362 (1200 3100);
PAINT SKYBLUE (1200 3100);
FORCEPROP 1 LAST PACK_TYPE 0402LF
J 0
(1200 3050);
DISPLAY 0.489362 (1200 3050);
PAINT SKYBLUE (1200 3050);
FORCEPROP 2 LAST CDS_LIB pure_quanta
J 0
(1150 3225);
DISPLAY INVISIBLE (1150 3225);
FORCEPROP 1 LAST PATH I130
J 0
(1200 3400);
DISPLAY 0.978723 (1200 3400);
PAINT WHITE (1200 3400);
DISPLAY INVISIBLE (1200 3400);
FORCEADD Q_CAP..1
(1500 3250);
FORCEPROP 1 LAST LOCATION PC144_IOP0_2
J 0
(1550 3350);
DISPLAY 0.489362 (1550 3350);
PAINT SKYBLUE (1550 3350);
FORCEPROP 0 LAST $SEC 1
J 0
(1550 3400);
DISPLAY 0.680851 (1550 3400);
PAINT MONO (1550 3400);
DISPLAY INVISIBLE (1550 3400);
FORCEPROP 0 LAST CDS_SEC 1
J 0
(1550 3400);
DISPLAY 1.021277 (1550 3400);
DISPLAY INVISIBLE (1550 3400);
FORCEPROP 1 LASTPIN (1500 3350) $PN 1
J 0
(1510 3330);
DISPLAY 0.489362 (1510 3330);
PAINT MONO (1510 3330);
FORCEPROP 1 LASTPIN (1500 3150) $PN 2
J 0
(1510 3130);
DISPLAY 0.489362 (1510 3130);
PAINT MONO (1510 3130);
FORCEPROP 1 LAST VOLTAGE 10V
J 0
(1550 3250);
DISPLAY 0.489362 (1550 3250);
PAINT SKYBLUE (1550 3250);
FORCEPROP 1 LAST VALUE 2.2UF
J 0
(1550 3300);
DISPLAY 0.489362 (1550 3300);
PAINT SKYBLUE (1550 3300);
FORCEPROP 1 LAST PART_NUMBER CH5222KEB01
J 0
(1550 3100);
DISPLAY 0.489362 (1550 3100);
PAINT SKYBLUE (1550 3100);
FORCEPROP 1 LAST PACK_TYPE C0402
J 0
(1550 3050);
DISPLAY 0.489362 (1550 3050);
PAINT SKYBLUE (1550 3050);
FORCEPROP 1 LAST TOLERANCE 10%
J 0
(1550 3200);
DISPLAY 0.489362 (1550 3200);
PAINT SKYBLUE (1550 3200);
FORCEPROP 1 LAST MATERIAL X6S
J 0
(1550 3150);
DISPLAY 0.489362 (1550 3150);
PAINT SKYBLUE (1550 3150);
FORCEPROP 2 LAST CDS_LIB pure_quanta
J 0
(1500 3250);
DISPLAY INVISIBLE (1500 3250);
FORCEPROP 1 LAST PATH I131
J 0
(1550 3400);
DISPLAY 0.978723 (1550 3400);
PAINT WHITE (1550 3400);
DISPLAY INVISIBLE (1550 3400);
FORCEADD UNIVERSAL_GND..1
(225 4450);
FORCEPROP 3 LASTPIN (225 4500) SIG_NAME GND\g
J 0
(235 4510);
DISPLAY 0.659574 (235 4510);
PAINT MONO (235 4510);
DISPLAY INVISIBLE (235 4510);
FORCEPROP 2 LAST CDS_LIB pure_quanta_power
J 0
(225 4450);
DISPLAY INVISIBLE (225 4450);
FORCEPROP 1 LAST PATH I133
J 0
(300 4450);
DISPLAY 0.872340 (300 4450);
PAINT AQUA (300 4450);
DISPLAY INVISIBLE (300 4450);
FORCEPROP 1 LAST HDL_POWER GND
J 1
(250 4375);
DISPLAY 0.872340 (250 4375);
PAINT GREEN (250 4375);
DISPLAY INVISIBLE (250 4375);
FORCEADD UNIVERSAL_GND..1
(250 1700);
FORCEPROP 3 LASTPIN (250 1750) SIG_NAME GND\g
J 0
(260 1760);
DISPLAY 0.659574 (260 1760);
PAINT MONO (260 1760);
DISPLAY INVISIBLE (260 1760);
FORCEPROP 2 LAST CDS_LIB pure_quanta_power
J 0
(250 1700);
DISPLAY INVISIBLE (250 1700);
FORCEPROP 1 LAST PATH I134
J 0
(325 1700);
DISPLAY 0.872340 (325 1700);
PAINT AQUA (325 1700);
DISPLAY INVISIBLE (325 1700);
FORCEPROP 1 LAST HDL_POWER GND
J 1
(275 1625);
DISPLAY 0.872340 (275 1625);
PAINT GREEN (275 1625);
DISPLAY INVISIBLE (275 1625);
FORCEADD OFFPAGE..3
(7050 2025);
FORCEPROP 2 LAST $XR0 181 
J 0
(7294 2025);
DISPLAY 0.638298 (7294 2025);
PAINT MONO (7294 2025);
FORCEPROP 2 LAST CDS_LIB standard
J 0
(7050 2025);
DISPLAY INVISIBLE (7050 2025);
FORCEPROP 1 LAST OFFPAGE TRUE
J 0
(7375 1900);
DISPLAY 0.872340 (7375 1900);
PAINT GREEN (7375 1900);
DISPLAY INVISIBLE (7375 1900);
FORCEPROP 1 LAST COMMENT_BODY TRUE
J 0
(7000 1925);
DISPLAY 0.872340 (7000 1925);
PAINT GREEN (7000 1925);
DISPLAY INVISIBLE (7000 1925);
FORCEPROP 2 LAST PATH I135
J 0
(7250 2100);
DISPLAY 1.021277 (7250 2100);
DISPLAY INVISIBLE (7250 2100);
FORCEADD UNIVERSAL_GND..1
(4300 4100);
FORCEPROP 3 LASTPIN (4300 4150) SIG_NAME GND\g
J 0
(4310 4160);
DISPLAY 0.659574 (4310 4160);
PAINT MONO (4310 4160);
DISPLAY INVISIBLE (4310 4160);
FORCEPROP 2 LAST CDS_LIB pure_quanta_power
J 0
(4300 4100);
DISPLAY INVISIBLE (4300 4100);
FORCEPROP 1 LAST PATH I136
J 0
(4375 4100);
DISPLAY 0.872340 (4375 4100);
PAINT AQUA (4375 4100);
DISPLAY INVISIBLE (4375 4100);
FORCEPROP 1 LAST HDL_POWER GND
J 1
(4325 4025);
DISPLAY 0.872340 (4325 4025);
PAINT GREEN (4325 4025);
DISPLAY INVISIBLE (4325 4025);
FORCEADD Q_RES..2
(4300 4325);
FORCEPROP 1 LAST LOCATION PR221
J 0
(4345 4450);
DISPLAY 0.489362 (4345 4450);
PAINT SKYBLUE (4345 4450);
FORCEPROP 0 LAST $SEC 1
J 0
(4350 4500);
DISPLAY 0.680851 (4350 4500);
PAINT MONO (4350 4500);
DISPLAY INVISIBLE (4350 4500);
FORCEPROP 0 LAST CDS_SEC 1
J 0
(4350 4500);
DISPLAY 1.021277 (4350 4500);
DISPLAY INVISIBLE (4350 4500);
FORCEPROP 1 LASTPIN (4300 4425) $PN 1
J 0
(4305 4387);
DISPLAY 0.489362 (4305 4387);
PAINT MONO (4305 4387);
FORCEPROP 1 LASTPIN (4300 4225) $PN 2
J 0
(4305 4235);
DISPLAY 0.489362 (4305 4235);
PAINT MONO (4305 4235);
FORCEPROP 1 LAST TOLERANCE 1%
J 0
(4345 4350);
DISPLAY 0.489362 (4345 4350);
PAINT SKYBLUE (4345 4350);
FORCEPROP 1 LAST WATTAGE 1/8W
J 0
(4340 4300);
DISPLAY 0.489362 (4340 4300);
PAINT SKYBLUE (4340 4300);
FORCEPROP 1 LAST MATERIAL EMPTY
J 0
(4340 4250);
DISPLAY 0.489362 (4340 4250);
PAINT RED (4340 4250);
FORCEPROP 1 LAST VALUE 1.5
J 0
(4345 4400);
DISPLAY 0.489362 (4345 4400);
PAINT SKYBLUE (4345 4400);
FORCEPROP 1 LAST PART_NUMBER CS-1504FB00
J 0
(4340 4200);
DISPLAY 0.489362 (4340 4200);
PAINT SKYBLUE (4340 4200);
FORCEPROP 1 LAST PACK_TYPE 0402LF
J 0
(4340 4150);
DISPLAY 0.489362 (4340 4150);
PAINT SKYBLUE (4340 4150);
FORCEPROP 2 LAST CDS_LIB pure_quanta
J 0
(4300 4325);
DISPLAY INVISIBLE (4300 4325);
FORCEPROP 1 LAST PATH I137
J 0
(4350 4500);
DISPLAY 0.978723 (4350 4500);
PAINT WHITE (4350 4500);
DISPLAY INVISIBLE (4350 4500);
FORCEADD Q_CAP..1
(4300 4875);
FORCEPROP 1 LAST LOCATION PC158
J 0
(4350 4975);
DISPLAY 0.489362 (4350 4975);
PAINT SKYBLUE (4350 4975);
FORCEPROP 0 LAST $SEC 1
J 0
(4350 5025);
DISPLAY 0.680851 (4350 5025);
PAINT MONO (4350 5025);
DISPLAY INVISIBLE (4350 5025);
FORCEPROP 0 LAST CDS_SEC 1
J 0
(4350 5025);
DISPLAY 1.021277 (4350 5025);
DISPLAY INVISIBLE (4350 5025);
FORCEPROP 1 LASTPIN (4300 4975) $PN 1
J 0
(4310 4955);
DISPLAY 0.489362 (4310 4955);
PAINT MONO (4310 4955);
FORCEPROP 1 LASTPIN (4300 4775) $PN 2
J 0
(4310 4755);
DISPLAY 0.489362 (4310 4755);
PAINT MONO (4310 4755);
FORCEPROP 1 LAST MATERIAL EMPTY
J 0
(4350 4775);
DISPLAY 0.489362 (4350 4775);
PAINT RED (4350 4775);
FORCEPROP 1 LAST TOLERANCE 10%
J 0
(4350 4825);
DISPLAY 0.489362 (4350 4825);
PAINT SKYBLUE (4350 4825);
FORCEPROP 1 LAST VALUE 560PF
J 0
(4350 4925);
DISPLAY 0.489362 (4350 4925);
PAINT SKYBLUE (4350 4925);
FORCEPROP 1 LAST PART_NUMBER CH1566K1B09
J 0
(4350 4725);
DISPLAY 0.489362 (4350 4725);
PAINT SKYBLUE (4350 4725);
FORCEPROP 1 LAST VOLTAGE 50V
J 0
(4350 4875);
DISPLAY 0.489362 (4350 4875);
PAINT SKYBLUE (4350 4875);
FORCEPROP 1 LAST PACK_TYPE C0402
J 0
(4350 4675);
DISPLAY 0.489362 (4350 4675);
PAINT SKYBLUE (4350 4675);
FORCEPROP 2 LAST CDS_LIB pure_quanta
J 0
(4300 4875);
DISPLAY INVISIBLE (4300 4875);
FORCEPROP 1 LAST PATH I138
J 0
(4350 5025);
DISPLAY 0.978723 (4350 5025);
PAINT WHITE (4350 5025);
DISPLAY INVISIBLE (4350 5025);
FORCEADD UNIVERSAL_GND..1
(4300 1350);
FORCEPROP 3 LASTPIN (4300 1400) SIG_NAME GND\g
J 0
(4310 1410);
DISPLAY 0.659574 (4310 1410);
PAINT MONO (4310 1410);
DISPLAY INVISIBLE (4310 1410);
FORCEPROP 2 LAST CDS_LIB pure_quanta_power
J 0
(4300 1350);
DISPLAY INVISIBLE (4300 1350);
FORCEPROP 1 LAST PATH I139
J 0
(4375 1350);
DISPLAY 0.872340 (4375 1350);
PAINT AQUA (4375 1350);
DISPLAY INVISIBLE (4375 1350);
FORCEPROP 1 LAST HDL_POWER GND
J 1
(4325 1275);
DISPLAY 0.872340 (4325 1275);
PAINT GREEN (4325 1275);
DISPLAY INVISIBLE (4325 1275);
FORCEADD Q_RES..2
(4300 1575);
FORCEPROP 1 LAST LOCATION PR223
J 0
(4345 1700);
DISPLAY 0.489362 (4345 1700);
PAINT SKYBLUE (4345 1700);
FORCEPROP 0 LAST $SEC 1
J 0
(4350 1750);
DISPLAY 0.680851 (4350 1750);
PAINT MONO (4350 1750);
DISPLAY INVISIBLE (4350 1750);
FORCEPROP 0 LAST CDS_SEC 1
J 0
(4350 1750);
DISPLAY 1.021277 (4350 1750);
DISPLAY INVISIBLE (4350 1750);
FORCEPROP 1 LASTPIN (4300 1675) $PN 1
J 0
(4305 1637);
DISPLAY 0.489362 (4305 1637);
PAINT MONO (4305 1637);
FORCEPROP 1 LASTPIN (4300 1475) $PN 2
J 0
(4305 1485);
DISPLAY 0.489362 (4305 1485);
PAINT MONO (4305 1485);
FORCEPROP 1 LAST WATTAGE 1/8W
J 0
(4340 1550);
DISPLAY 0.489362 (4340 1550);
PAINT SKYBLUE (4340 1550);
FORCEPROP 1 LAST MATERIAL EMPTY
J 0
(4340 1500);
DISPLAY 0.489362 (4340 1500);
PAINT RED (4340 1500);
FORCEPROP 1 LAST TOLERANCE 1%
J 0
(4345 1600);
DISPLAY 0.489362 (4345 1600);
PAINT SKYBLUE (4345 1600);
FORCEPROP 1 LAST VALUE 1.5
J 0
(4345 1650);
DISPLAY 0.489362 (4345 1650);
PAINT SKYBLUE (4345 1650);
FORCEPROP 1 LAST PART_NUMBER CS-1504FB00
J 0
(4340 1450);
DISPLAY 0.489362 (4340 1450);
PAINT SKYBLUE (4340 1450);
FORCEPROP 1 LAST PACK_TYPE 0402LF
J 0
(4340 1400);
DISPLAY 0.489362 (4340 1400);
PAINT SKYBLUE (4340 1400);
FORCEPROP 2 LAST CDS_LIB pure_quanta
J 0
(4300 1575);
DISPLAY INVISIBLE (4300 1575);
FORCEPROP 1 LAST PATH I140
J 0
(4350 1750);
DISPLAY 0.978723 (4350 1750);
PAINT WHITE (4350 1750);
DISPLAY INVISIBLE (4350 1750);
FORCEADD Q_CAP..1
(4300 2075);
FORCEPROP 1 LAST LOCATION PC159
J 0
(4350 2175);
DISPLAY 0.489362 (4350 2175);
PAINT SKYBLUE (4350 2175);
FORCEPROP 0 LAST $SEC 1
J 0
(4350 2225);
DISPLAY 0.680851 (4350 2225);
PAINT MONO (4350 2225);
DISPLAY INVISIBLE (4350 2225);
FORCEPROP 0 LAST CDS_SEC 1
J 0
(4350 2225);
DISPLAY 1.021277 (4350 2225);
DISPLAY INVISIBLE (4350 2225);
FORCEPROP 1 LASTPIN (4300 2175) $PN 1
J 0
(4310 2155);
DISPLAY 0.489362 (4310 2155);
PAINT MONO (4310 2155);
FORCEPROP 1 LASTPIN (4300 1975) $PN 2
J 0
(4310 1955);
DISPLAY 0.489362 (4310 1955);
PAINT MONO (4310 1955);
FORCEPROP 1 LAST MATERIAL EMPTY
J 0
(4350 1975);
DISPLAY 0.489362 (4350 1975);
PAINT RED (4350 1975);
FORCEPROP 1 LAST TOLERANCE 10%
J 0
(4350 2025);
DISPLAY 0.489362 (4350 2025);
PAINT SKYBLUE (4350 2025);
FORCEPROP 1 LAST VALUE 560PF
J 0
(4350 2125);
DISPLAY 0.489362 (4350 2125);
PAINT SKYBLUE (4350 2125);
FORCEPROP 1 LAST PART_NUMBER CH1566K1B09
J 0
(4350 1925);
DISPLAY 0.489362 (4350 1925);
PAINT SKYBLUE (4350 1925);
FORCEPROP 1 LAST VOLTAGE 50V
J 0
(4350 2075);
DISPLAY 0.489362 (4350 2075);
PAINT SKYBLUE (4350 2075);
FORCEPROP 1 LAST PACK_TYPE C0402
J 0
(4350 1875);
DISPLAY 0.489362 (4350 1875);
PAINT SKYBLUE (4350 1875);
FORCEPROP 2 LAST CDS_LIB pure_quanta
J 0
(4300 2075);
DISPLAY INVISIBLE (4300 2075);
FORCEPROP 1 LAST PATH I141
J 0
(4350 2225);
DISPLAY 0.978723 (4350 2225);
PAINT WHITE (4350 2225);
DISPLAY INVISIBLE (4350 2225);
FORCEADD VCC_CORE..1
(1250 6325);
FORCEPROP 3 LASTPIN (1250 6275) SIG_NAME PVDDCR_CPU1_P0_PVCC\g
J 0
(1260 6285);
DISPLAY 0.659574 (1260 6285);
PAINT MONO (1260 6285);
DISPLAY INVISIBLE (1260 6285);
FORCEPROP 1 LAST HDL_POWER PVDDCR_CPU1_P0_PVCC
J 1
(1250 6375);
DISPLAY 0.489362 (1250 6375);
PAINT GREEN (1250 6375);
FORCEPROP 2 LAST CDS_LIB pure_quanta_power
J 0
(1250 6325);
DISPLAY INVISIBLE (1250 6325);
FORCEPROP 1 LAST PATH I142
J 0
(1300 6350);
DISPLAY 0.872340 (1300 6350);
PAINT AQUA (1300 6350);
DISPLAY INVISIBLE (1300 6350);
FORCEADD VCC_CORE..1
(1150 3650);
FORCEPROP 3 LASTPIN (1150 3600) SIG_NAME PVDDCR_CPU1_P0_PVCC\g
J 0
(1160 3610);
DISPLAY 0.659574 (1160 3610);
PAINT MONO (1160 3610);
DISPLAY INVISIBLE (1160 3610);
FORCEPROP 1 LAST HDL_POWER PVDDCR_CPU1_P0_PVCC
J 1
(1150 3700);
DISPLAY 0.489362 (1150 3700);
PAINT GREEN (1150 3700);
FORCEPROP 2 LAST CDS_LIB pure_quanta_power
J 0
(1150 3650);
DISPLAY INVISIBLE (1150 3650);
FORCEPROP 1 LAST PATH I143
J 0
(1200 3675);
DISPLAY 0.872340 (1200 3675);
PAINT AQUA (1200 3675);
DISPLAY INVISIBLE (1200 3675);
FORCEADD Q_RES..2
(8400 4875);
FORCEPROP 1 LAST LOCATION PR410
J 0
(8445 5000);
DISPLAY 0.489362 (8445 5000);
PAINT SKYBLUE (8445 5000);
FORCEPROP 0 LAST $SEC 1
J 0
(8450 5025);
DISPLAY 0.680851 (8450 5025);
PAINT MONO (8450 5025);
DISPLAY INVISIBLE (8450 5025);
FORCEPROP 0 LAST CDS_SEC 1
J 0
(8450 5025);
DISPLAY 1.021277 (8450 5025);
DISPLAY INVISIBLE (8450 5025);
FORCEPROP 1 LASTPIN (8400 4975) $PN 1
J 0
(8405 4937);
DISPLAY 0.787234 (8405 4937);
PAINT MONO (8405 4937);
DISPLAY INVISIBLE (8405 4937);
FORCEPROP 1 LASTPIN (8400 4775) $PN 2
J 0
(8405 4785);
DISPLAY 0.787234 (8405 4785);
PAINT MONO (8405 4785);
DISPLAY INVISIBLE (8405 4785);
FORCEPROP 1 LAST WATTAGE 1/16W
J 0
(8440 4850);
DISPLAY 0.489362 (8440 4850);
PAINT SKYBLUE (8440 4850);
FORCEPROP 1 LAST MATERIAL CHIP
J 0
(8440 4800);
DISPLAY 0.489362 (8440 4800);
PAINT SKYBLUE (8440 4800);
FORCEPROP 1 LAST TOLERANCE 1%
J 0
(8445 4900);
DISPLAY 0.489362 (8445 4900);
PAINT SKYBLUE (8445 4900);
FORCEPROP 1 LAST VALUE 1K
J 0
(8445 4950);
DISPLAY 0.489362 (8445 4950);
PAINT SKYBLUE (8445 4950);
FORCEPROP 1 LAST PART_NUMBER TMP_QCS21002FB24
J 0
(8440 4750);
DISPLAY 0.489362 (8440 4750);
PAINT SKYBLUE (8440 4750);
FORCEPROP 1 LAST PACK_TYPE 0402LF
J 0
(8440 4700);
DISPLAY 0.489362 (8440 4700);
PAINT SKYBLUE (8440 4700);
FORCEPROP 2 LAST CDS_LIB pure_quanta
J 0
(8400 4875);
DISPLAY INVISIBLE (8400 4875);
FORCEPROP 1 LAST PATH I144
J 0
(8450 5050);
DISPLAY 0.978723 (8450 5050);
PAINT WHITE (8450 5050);
DISPLAY INVISIBLE (8450 5050);
FORCEADD OFFPAGE..6
(5000 4825);
FORCEPROP 2 LAST $XR0 181 
J 0
(4690 4825);
DISPLAY 0.638298 (4690 4825);
PAINT MONO (4690 4825);
FORCEPROP 1 LAST COMMENT_BODY TRUE
J 0
(5100 4750);
DISPLAY 0.872340 (5100 4750);
PAINT GREEN (5100 4750);
DISPLAY INVISIBLE (5100 4750);
FORCEPROP 1 LAST OFFPAGE TRUE
J 0
(5325 4700);
DISPLAY 0.872340 (5325 4700);
PAINT GREEN (5325 4700);
DISPLAY INVISIBLE (5325 4700);
FORCEPROP 2 LAST CDS_LIB standard
J 0
(5000 4825);
DISPLAY INVISIBLE (5000 4825);
FORCEPROP 2 LAST PATH I145
J 0
(4725 4875);
DISPLAY 1.021277 (4725 4875);
DISPLAY INVISIBLE (4725 4875);
FORCEADD UNIVERSAL_GND..1
(6900 4700);
FORCEPROP 3 LASTPIN (6900 4750) SIG_NAME GND\g
J 0
(6910 4760);
DISPLAY 0.659574 (6910 4760);
PAINT MONO (6910 4760);
DISPLAY INVISIBLE (6910 4760);
FORCEPROP 2 LAST CDS_LIB pure_quanta_power
J 0
(6900 4700);
DISPLAY INVISIBLE (6900 4700);
FORCEPROP 1 LAST PATH I146
J 0
(6975 4700);
DISPLAY 0.872340 (6975 4700);
PAINT AQUA (6975 4700);
DISPLAY INVISIBLE (6975 4700);
FORCEPROP 1 LAST HDL_POWER GND
J 1
(6925 4625);
DISPLAY 0.872340 (6925 4625);
PAINT GREEN (6925 4625);
DISPLAY INVISIBLE (6925 4625);
FORCEADD OFFPAGE..1
(1300 4475);
FORCEPROP 2 LAST $XR0 176 
J 0
(1018 4475);
DISPLAY 0.638298 (1018 4475);
PAINT MONO (1018 4475);
FORCEPROP 2 LAST CDS_LIB standard
J 0
(1300 4475);
DISPLAY INVISIBLE (1300 4475);
FORCEPROP 1 LAST OFFPAGE TRUE
J 0
(1625 4350);
DISPLAY 0.872340 (1625 4350);
PAINT GREEN (1625 4350);
DISPLAY INVISIBLE (1625 4350);
FORCEPROP 1 LAST COMMENT_BODY TRUE
J 0
(1425 4375);
DISPLAY 0.872340 (1425 4375);
PAINT GREEN (1425 4375);
DISPLAY INVISIBLE (1425 4375);
FORCEPROP 2 LAST PATH I16
J 0
(875 4525);
DISPLAY 1.021277 (875 4525);
DISPLAY INVISIBLE (875 4525);
FORCEADD Q_RES..2
R 2
(850 4625);
FORCEPROP 1 LAST LOCATION PR98
J 2
(805 4750);
DISPLAY 0.489362 (805 4750);
PAINT SKYBLUE (805 4750);
FORCEPROP 0 LAST $SEC 1
J 2
(800 4800);
DISPLAY 0.680851 (800 4800);
PAINT MONO (800 4800);
DISPLAY INVISIBLE (800 4800);
FORCEPROP 0 LAST CDS_SEC 1
J 2
(800 4800);
DISPLAY 1.021277 (800 4800);
DISPLAY INVISIBLE (800 4800);
FORCEPROP 1 LASTPIN (850 4725) $PN 1
J 2
(845 4687);
DISPLAY 0.489362 (845 4687);
PAINT MONO (845 4687);
FORCEPROP 1 LASTPIN (850 4525) $PN 2
J 2
(845 4535);
DISPLAY 0.489362 (845 4535);
PAINT MONO (845 4535);
FORCEPROP 1 LAST MATERIAL EMPTY
J 2
(800 4550);
DISPLAY 0.489362 (800 4550);
PAINT RED (800 4550);
FORCEPROP 1 LAST VALUE 8.87K
J 2
(795 4700);
DISPLAY 0.489362 (795 4700);
PAINT SKYBLUE (795 4700);
FORCEPROP 1 LAST PART_NUMBER CS28872FB01
J 2
(800 4500);
DISPLAY 0.489362 (800 4500);
PAINT SKYBLUE (800 4500);
FORCEPROP 1 LAST PACK_TYPE 0402LF
J 2
(800 4450);
DISPLAY 0.489362 (800 4450);
PAINT SKYBLUE (800 4450);
FORCEPROP 1 LAST WATTAGE 1/16W
J 2
(800 4600);
DISPLAY 0.489362 (800 4600);
PAINT SKYBLUE (800 4600);
FORCEPROP 1 LAST TOLERANCE 1%
J 2
(795 4650);
DISPLAY 0.489362 (795 4650);
PAINT SKYBLUE (795 4650);
FORCEPROP 2 LAST CDS_LIB pure_quanta
J 2
(850 4625);
DISPLAY INVISIBLE (850 4625);
FORCEPROP 1 LAST PATH I17
J 2
(800 4800);
DISPLAY 0.978723 (800 4800);
PAINT WHITE (800 4800);
DISPLAY INVISIBLE (800 4800);
FORCEADD Q_RES..2
R 2
(825 1775);
FORCEPROP 1 LAST LOCATION PR97
J 2
(780 1900);
DISPLAY 0.489362 (780 1900);
PAINT SKYBLUE (780 1900);
FORCEPROP 0 LAST $SEC 1
J 2
(775 1950);
DISPLAY 0.680851 (775 1950);
PAINT MONO (775 1950);
DISPLAY INVISIBLE (775 1950);
FORCEPROP 0 LAST CDS_SEC 1
J 2
(775 1950);
DISPLAY 1.021277 (775 1950);
DISPLAY INVISIBLE (775 1950);
FORCEPROP 1 LASTPIN (825 1875) $PN 1
J 2
(820 1837);
DISPLAY 0.489362 (820 1837);
PAINT MONO (820 1837);
FORCEPROP 1 LASTPIN (825 1675) $PN 2
J 2
(820 1685);
DISPLAY 0.489362 (820 1685);
PAINT MONO (820 1685);
FORCEPROP 1 LAST WATTAGE 1/16W
J 2
(775 1750);
DISPLAY 0.489362 (775 1750);
PAINT SKYBLUE (775 1750);
FORCEPROP 1 LAST MATERIAL EMPTY
J 2
(775 1700);
DISPLAY 0.489362 (775 1700);
PAINT RED (775 1700);
FORCEPROP 1 LAST TOLERANCE 1%
J 2
(770 1800);
DISPLAY 0.489362 (770 1800);
PAINT SKYBLUE (770 1800);
FORCEPROP 1 LAST VALUE 8.87K
J 2
(770 1850);
DISPLAY 0.489362 (770 1850);
PAINT SKYBLUE (770 1850);
FORCEPROP 1 LAST PART_NUMBER CS28872FB01
J 2
(775 1650);
DISPLAY 0.489362 (775 1650);
PAINT SKYBLUE (775 1650);
FORCEPROP 1 LAST PACK_TYPE 0402LF
J 2
(775 1600);
DISPLAY 0.489362 (775 1600);
PAINT SKYBLUE (775 1600);
FORCEPROP 2 LAST CDS_LIB pure_quanta
J 2
(825 1775);
DISPLAY INVISIBLE (825 1775);
FORCEPROP 1 LAST PATH I2
J 2
(775 1950);
DISPLAY 0.978723 (775 1950);
PAINT WHITE (775 1950);
DISPLAY INVISIBLE (775 1950);
FORCEADD OFFPAGE..1
(1300 4975);
FORCEPROP 2 LAST $XR5 182 
J 0
(418 4975);
DISPLAY 0.638298 (418 4975);
PAINT MONO (418 4975);
FORCEPROP 2 LAST $XR4 181 
J 0
(538 4975);
DISPLAY 0.638298 (538 4975);
PAINT MONO (538 4975);
FORCEPROP 2 LAST $XR3 179 
J 0
(658 4975);
DISPLAY 0.638298 (658 4975);
PAINT MONO (658 4975);
FORCEPROP 2 LAST $XR2 178 
J 0
(778 4975);
DISPLAY 0.638298 (778 4975);
PAINT MONO (778 4975);
FORCEPROP 2 LAST $XR1 177 
J 0
(898 4975);
DISPLAY 0.638298 (898 4975);
PAINT MONO (898 4975);
FORCEPROP 2 LAST $XR0 176 
J 0
(1018 4975);
DISPLAY 0.638298 (1018 4975);
PAINT MONO (1018 4975);
FORCEPROP 2 LAST CDS_LIB standard
J 0
(1300 4975);
DISPLAY INVISIBLE (1300 4975);
FORCEPROP 1 LAST OFFPAGE TRUE
J 0
(1625 4850);
DISPLAY 0.872340 (1625 4850);
PAINT GREEN (1625 4850);
DISPLAY INVISIBLE (1625 4850);
FORCEPROP 1 LAST COMMENT_BODY TRUE
J 0
(1425 4875);
DISPLAY 0.872340 (1425 4875);
PAINT GREEN (1425 4875);
DISPLAY INVISIBLE (1425 4875);
FORCEPROP 2 LAST PATH I20
J 0
(1050 5025);
DISPLAY 1.021277 (1050 5025);
DISPLAY INVISIBLE (1050 5025);
FORCEADD OFFPAGE..5
(1300 5075);
FORCEPROP 2 LAST $XR0 176 
J 0
(1045 5075);
DISPLAY 0.638298 (1045 5075);
PAINT MONO (1045 5075);
FORCEPROP 2 LAST CDS_LIB standard
J 0
(1300 5075);
DISPLAY INVISIBLE (1300 5075);
FORCEPROP 1 LAST OFFPAGE TRUE
J 0
(1625 4950);
DISPLAY 0.872340 (1625 4950);
PAINT GREEN (1625 4950);
DISPLAY INVISIBLE (1625 4950);
FORCEPROP 1 LAST COMMENT_BODY TRUE
J 0
(1400 5000);
DISPLAY 0.872340 (1400 5000);
PAINT GREEN (1400 5000);
DISPLAY INVISIBLE (1400 5000);
FORCEPROP 2 LAST PATH I21
J 0
(1050 5125);
DISPLAY 1.021277 (1050 5125);
DISPLAY INVISIBLE (1050 5125);
FORCEADD ISL99390FRZTR5935..1
(2825 2275);
FORCEPROP 1 LAST LOCATION PU18
J 0
(2525 3150);
DISPLAY 0.489362 (2525 3150);
PAINT SKYBLUE (2525 3150);
FORCEPROP 0 LAST $SEC 1
J 0
(2525 3325);
DISPLAY 0.680851 (2525 3325);
PAINT MONO (2525 3325);
DISPLAY INVISIBLE (2525 3325);
FORCEPROP 2 LAST CDS_SEC 1
J 0
(2575 3275);
DISPLAY 1.021277 (2575 3275);
DISPLAY INVISIBLE (2575 3275);
FORCEPROP 0 LASTPIN (3225 1825) $PN 2
J 0
(3235 1835);
DISPLAY 0.489362 (3235 1835);
PAINT MONO (3235 1835);
FORCEPROP 0 LASTPIN (3225 2625) $PN 33
J 0
(3235 2635);
DISPLAY 0.489362 (3235 2635);
PAINT MONO (3235 2635);
FORCEPROP 0 LASTPIN (2375 2025) $PN 31
J 2
(2365 2035);
DISPLAY 0.489362 (2365 2035);
PAINT MONO (2365 2035);
FORCEPROP 0 LASTPIN (2375 2425) $PN 35
J 2
(2365 2435);
DISPLAY 0.489362 (2365 2435);
PAINT MONO (2365 2435);
FORCEPROP 0 LASTPIN (3225 1975) $PN 6
J 0
(3235 1985);
DISPLAY 0.489362 (3235 1985);
PAINT MONO (3235 1985);
FORCEPROP 0 LASTPIN (3225 1925) $PN 41
J 0
(3235 1935);
DISPLAY 0.489362 (3235 1935);
PAINT MONO (3235 1935);
FORCEPROP 0 LASTPIN (2375 2275) $PN 38
J 2
(2365 2285);
DISPLAY 0.489362 (2365 2285);
PAINT MONO (2365 2285);
FORCEPROP 0 LASTPIN (2375 1975) $PN 37
J 2
(2365 1985);
DISPLAY 0.489362 (2365 1985);
PAINT MONO (2365 1985);
FORCEPROP 0 LASTPIN (3225 1775) $PN 5
J 0
(3235 1785);
DISPLAY 0.489362 (3235 1785);
PAINT MONO (3235 1785);
FORCEPROP 0 LASTPIN (3225 1725) $PN 7_9-20_24
J 0
(3235 1735);
DISPLAY 0.489362 (3235 1735);
PAINT MONO (3235 1735);
FORCEPROP 0 LASTPIN (3225 1675) $PN 40
J 0
(3235 1685);
DISPLAY 0.489362 (3235 1685);
PAINT MONO (3235 1685);
FORCEPROP 0 LASTPIN (3225 2375) $PN 32
J 0
(3235 2385);
DISPLAY 0.489362 (3235 2385);
PAINT MONO (3235 2385);
FORCEPROP 0 LASTPIN (2375 2925) $PN 4
J 2
(2365 2935);
DISPLAY 0.489362 (2365 2935);
PAINT MONO (2365 2935);
FORCEPROP 0 LASTPIN (2375 1675) $PN 34
J 2
(2365 1685);
DISPLAY 0.489362 (2365 1685);
PAINT MONO (2365 1685);
FORCEPROP 0 LASTPIN (2375 2175) $PN 39
J 2
(2365 2185);
DISPLAY 0.489362 (2365 2185);
PAINT MONO (2365 2185);
FORCEPROP 0 LASTPIN (3225 2275) $PN 10_19
J 0
(3235 2285);
DISPLAY 0.489362 (3235 2285);
PAINT MONO (3235 2285);
FORCEPROP 0 LASTPIN (2375 1775) $PN 36
J 2
(2365 1785);
DISPLAY 0.489362 (2365 1785);
PAINT MONO (2365 1785);
FORCEPROP 0 LASTPIN (2375 2625) $PN 3
J 2
(2365 2635);
DISPLAY 0.489362 (2365 2635);
PAINT MONO (2365 2635);
FORCEPROP 0 LASTPIN (3225 2925) $PN 25_29
J 0
(3235 2935);
DISPLAY 0.489362 (3235 2935);
PAINT MONO (3235 2935);
FORCEPROP 0 LASTPIN (3225 2875) $PN 30
J 0
(3235 2885);
DISPLAY 0.489362 (3235 2885);
PAINT MONO (3235 2885);
FORCEPROP 0 LASTPIN (3225 2025) $PN 1
J 0
(3235 2035);
DISPLAY 0.489362 (3235 2035);
PAINT MONO (3235 2035);
FORCEPROP 1 LAST MATERIAL IC
J 0
(2525 3000);
DISPLAY 0.489362 (2525 3000);
PAINT SKYBLUE (2525 3000);
FORCEPROP 2 LAST PART_TYPE SMLF
J 0
(2525 3275);
DISPLAY 0.638298 (2525 3275);
FORCEPROP 2 LAST VALUE ISL99390FRZ-TR5935
J 0
(2525 3225);
DISPLAY 0.489362 (2525 3225);
PAINT SKYBLUE (2525 3225);
FORCEPROP 1 LAST PART_NUMBER AL099390004
J 0
(2525 3075);
DISPLAY 0.489362 (2525 3075);
PAINT SKYBLUE (2525 3075);
FORCEPROP 2 LAST CDS_LIB pure_quanta
J 0
(2825 2275);
DISPLAY INVISIBLE (2825 2275);
FORCEPROP 1 LAST NEEDS_NO_SIZE TRUE
J 0
(2825 2275);
DISPLAY 0.723404 (2825 2275);
PAINT GREEN (2825 2275);
DISPLAY INVISIBLE (2825 2275);
FORCEPROP 1 LAST CDS_LMAN_SYM_OUTLINE -300,700,250,-650
J 0
(2825 2275);
DISPLAY 0.468085 (2825 2275);
PAINT GREEN (2825 2275);
DISPLAY INVISIBLE (2825 2275);
FORCEPROP 1 LAST PATH I30
J 0
(2825 2275);
DISPLAY 0.723404 (2825 2275);
PAINT GREEN (2825 2275);
DISPLAY INVISIBLE (2825 2275);
FORCEADD UNIVERSAL_GND..1
(3475 1550);
FORCEPROP 3 LASTPIN (3475 1600) SIG_NAME GND\g
J 0
(3485 1610);
DISPLAY 0.659574 (3485 1610);
PAINT MONO (3485 1610);
DISPLAY INVISIBLE (3485 1610);
FORCEPROP 2 LAST CDS_LIB pure_quanta_power
J 0
(3475 1550);
PAINT MONO (3475 1550);
DISPLAY INVISIBLE (3475 1550);
FORCEPROP 1 LAST PATH I31
J 0
(3550 1550);
DISPLAY 0.872340 (3550 1550);
PAINT AQUA (3550 1550);
DISPLAY INVISIBLE (3550 1550);
FORCEPROP 1 LAST HDL_POWER GND
J 1
(3500 1475);
DISPLAY 0.872340 (3500 1475);
PAINT GREEN (3500 1475);
DISPLAY INVISIBLE (3500 1475);
FORCEADD UNIVERSAL_GND..1
(3475 4350);
FORCEPROP 3 LASTPIN (3475 4400) SIG_NAME GND\g
J 0
(3485 4410);
DISPLAY 0.659574 (3485 4410);
PAINT MONO (3485 4410);
DISPLAY INVISIBLE (3485 4410);
FORCEPROP 2 LAST CDS_LIB pure_quanta_power
J 0
(3475 4350);
PAINT MONO (3475 4350);
DISPLAY INVISIBLE (3475 4350);
FORCEPROP 1 LAST PATH I34
J 0
(3550 4350);
DISPLAY 0.872340 (3550 4350);
PAINT AQUA (3550 4350);
DISPLAY INVISIBLE (3550 4350);
FORCEPROP 1 LAST HDL_POWER GND
J 1
(3500 4275);
DISPLAY 0.872340 (3500 4275);
PAINT GREEN (3500 4275);
DISPLAY INVISIBLE (3500 4275);
FORCEADD ISL99390FRZTR5935..1
(2825 5075);
FORCEPROP 1 LAST LOCATION PU17
J 0
(2525 5950);
DISPLAY 0.489362 (2525 5950);
PAINT SKYBLUE (2525 5950);
FORCEPROP 0 LAST $SEC 1
J 0
(2525 6150);
DISPLAY 0.680851 (2525 6150);
PAINT MONO (2525 6150);
DISPLAY INVISIBLE (2525 6150);
FORCEPROP 2 LAST CDS_SEC 1
J 0
(2575 6075);
DISPLAY 1.021277 (2575 6075);
DISPLAY INVISIBLE (2575 6075);
FORCEPROP 0 LASTPIN (3225 4625) $PN 2
J 0
(3235 4635);
DISPLAY 0.489362 (3235 4635);
PAINT MONO (3235 4635);
FORCEPROP 0 LASTPIN (3225 5425) $PN 33
J 0
(3235 5435);
DISPLAY 0.489362 (3235 5435);
PAINT MONO (3235 5435);
FORCEPROP 0 LASTPIN (2375 4825) $PN 31
J 2
(2365 4835);
DISPLAY 0.489362 (2365 4835);
PAINT MONO (2365 4835);
FORCEPROP 0 LASTPIN (2375 5225) $PN 35
J 2
(2365 5235);
DISPLAY 0.489362 (2365 5235);
PAINT MONO (2365 5235);
FORCEPROP 0 LASTPIN (3225 4775) $PN 6
J 0
(3235 4785);
DISPLAY 0.489362 (3235 4785);
PAINT MONO (3235 4785);
FORCEPROP 0 LASTPIN (3225 4725) $PN 41
J 0
(3235 4735);
DISPLAY 0.489362 (3235 4735);
PAINT MONO (3235 4735);
FORCEPROP 0 LASTPIN (2375 5075) $PN 38
J 2
(2365 5085);
DISPLAY 0.489362 (2365 5085);
PAINT MONO (2365 5085);
FORCEPROP 0 LASTPIN (2375 4775) $PN 37
J 2
(2365 4785);
DISPLAY 0.489362 (2365 4785);
PAINT MONO (2365 4785);
FORCEPROP 0 LASTPIN (3225 4575) $PN 5
J 0
(3235 4585);
DISPLAY 0.489362 (3235 4585);
PAINT MONO (3235 4585);
FORCEPROP 0 LASTPIN (3225 4525) $PN 7_9-20_24
J 0
(3235 4535);
DISPLAY 0.489362 (3235 4535);
PAINT MONO (3235 4535);
FORCEPROP 0 LASTPIN (3225 4475) $PN 40
J 0
(3235 4485);
DISPLAY 0.489362 (3235 4485);
PAINT MONO (3235 4485);
FORCEPROP 0 LASTPIN (3225 5175) $PN 32
J 0
(3235 5185);
DISPLAY 0.489362 (3235 5185);
PAINT MONO (3235 5185);
FORCEPROP 0 LASTPIN (2375 5725) $PN 4
J 2
(2365 5735);
DISPLAY 0.489362 (2365 5735);
PAINT MONO (2365 5735);
FORCEPROP 0 LASTPIN (2375 4475) $PN 34
J 2
(2365 4485);
DISPLAY 0.489362 (2365 4485);
PAINT MONO (2365 4485);
FORCEPROP 0 LASTPIN (2375 4975) $PN 39
J 2
(2365 4985);
DISPLAY 0.489362 (2365 4985);
PAINT MONO (2365 4985);
FORCEPROP 0 LASTPIN (3225 5075) $PN 10_19
J 0
(3235 5085);
DISPLAY 0.489362 (3235 5085);
PAINT MONO (3235 5085);
FORCEPROP 0 LASTPIN (2375 4575) $PN 36
J 2
(2365 4585);
DISPLAY 0.489362 (2365 4585);
PAINT MONO (2365 4585);
FORCEPROP 0 LASTPIN (2375 5425) $PN 3
J 2
(2365 5435);
DISPLAY 0.489362 (2365 5435);
PAINT MONO (2365 5435);
FORCEPROP 0 LASTPIN (3225 5725) $PN 25_29
J 0
(3235 5735);
DISPLAY 0.489362 (3235 5735);
PAINT MONO (3235 5735);
FORCEPROP 0 LASTPIN (3225 5675) $PN 30
J 0
(3235 5685);
DISPLAY 0.489362 (3235 5685);
PAINT MONO (3235 5685);
FORCEPROP 0 LASTPIN (3225 4825) $PN 1
J 0
(3235 4835);
DISPLAY 0.489362 (3235 4835);
PAINT MONO (3235 4835);
FORCEPROP 2 LAST PART_TYPE SMLF
J 0
(2525 6100);
DISPLAY 0.638298 (2525 6100);
FORCEPROP 1 LAST MATERIAL IC
J 0
(2525 5800);
DISPLAY 0.489362 (2525 5800);
PAINT SKYBLUE (2525 5800);
FORCEPROP 2 LAST VALUE ISL99390FRZ-TR5935
J 0
(2525 6050);
DISPLAY 0.489362 (2525 6050);
PAINT SKYBLUE (2525 6050);
FORCEPROP 1 LAST PART_NUMBER AL099390004
J 0
(2525 5875);
DISPLAY 0.489362 (2525 5875);
PAINT SKYBLUE (2525 5875);
FORCEPROP 2 LAST CDS_LIB pure_quanta
J 0
(2825 5075);
DISPLAY INVISIBLE (2825 5075);
FORCEPROP 1 LAST NEEDS_NO_SIZE TRUE
J 0
(2825 5075);
DISPLAY 0.723404 (2825 5075);
PAINT GREEN (2825 5075);
DISPLAY INVISIBLE (2825 5075);
FORCEPROP 1 LAST CDS_LMAN_SYM_OUTLINE -300,700,250,-650
J 0
(2825 5075);
DISPLAY 0.468085 (2825 5075);
PAINT GREEN (2825 5075);
DISPLAY INVISIBLE (2825 5075);
FORCEPROP 1 LAST PATH I35
J 0
(2825 5075);
DISPLAY 0.723404 (2825 5075);
PAINT GREEN (2825 5075);
DISPLAY INVISIBLE (2825 5075);
FORCEADD Q_CAP..1
(4150 3200);
FORCEPROP 1 LAST LOCATION PC151_2
J 0
(4200 3350);
DISPLAY 0.489362 (4200 3350);
PAINT SKYBLUE (4200 3350);
FORCEPROP 0 LAST $SEC 1
J 0
(4200 3400);
DISPLAY 0.680851 (4200 3400);
PAINT MONO (4200 3400);
DISPLAY INVISIBLE (4200 3400);
FORCEPROP 0 LAST CDS_SEC 1
J 0
(4200 3400);
DISPLAY 1.021277 (4200 3400);
DISPLAY INVISIBLE (4200 3400);
FORCEPROP 1 LASTPIN (4150 3300) $PN 1
J 0
(4160 3280);
DISPLAY 0.489362 (4160 3280);
PAINT MONO (4160 3280);
FORCEPROP 1 LASTPIN (4150 3100) $PN 2
J 0
(4160 3080);
DISPLAY 0.489362 (4160 3080);
PAINT MONO (4160 3080);
FORCEPROP 1 LAST MATERIAL X6S
J 0
(4200 3150);
DISPLAY 0.489362 (4200 3150);
PAINT SKYBLUE (4200 3150);
FORCEPROP 1 LAST TOLERANCE 10%
J 0
(4200 3200);
DISPLAY 0.489362 (4200 3200);
PAINT SKYBLUE (4200 3200);
FORCEPROP 1 LAST VALUE 1UF
J 0
(4200 3300);
DISPLAY 0.489362 (4200 3300);
PAINT SKYBLUE (4200 3300);
FORCEPROP 1 LAST PART_NUMBER CH5104KEB02
J 0
(4200 3050);
DISPLAY 0.489362 (4200 3050);
PAINT SKYBLUE (4200 3050);
FORCEPROP 1 LAST VOLTAGE 25V
J 0
(4200 3250);
DISPLAY 0.489362 (4200 3250);
PAINT SKYBLUE (4200 3250);
FORCEPROP 1 LAST PACK_TYPE C0402
J 0
(4200 3100);
DISPLAY 0.489362 (4200 3100);
PAINT SKYBLUE (4200 3100);
FORCEPROP 2 LAST CDS_LIB pure_quanta
J 0
(4150 3200);
DISPLAY INVISIBLE (4150 3200);
FORCEPROP 1 LAST PATH I39
J 0
(4200 3350);
DISPLAY 0.978723 (4200 3350);
PAINT WHITE (4200 3350);
DISPLAY INVISIBLE (4200 3350);
FORCEADD OFFPAGE..1
(1275 1675);
FORCEPROP 2 LAST $XR0 176 
J 0
(1023 1675);
DISPLAY 0.638298 (1023 1675);
PAINT MONO (1023 1675);
FORCEPROP 2 LAST CDS_LIB standard
J 0
(1275 1675);
DISPLAY INVISIBLE (1275 1675);
FORCEPROP 1 LAST OFFPAGE TRUE
J 0
(1600 1550);
DISPLAY 0.872340 (1600 1550);
PAINT GREEN (1600 1550);
DISPLAY INVISIBLE (1600 1550);
FORCEPROP 1 LAST COMMENT_BODY TRUE
J 0
(1400 1575);
DISPLAY 0.872340 (1400 1575);
PAINT GREEN (1400 1575);
DISPLAY INVISIBLE (1400 1575);
FORCEPROP 2 LAST PATH I4
J 0
(850 1725);
DISPLAY 1.021277 (850 1725);
DISPLAY INVISIBLE (850 1725);
FORCEADD Q_CAP..1
(4550 3200);
FORCEPROP 1 LAST LOCATION PC153_2
J 0
(4600 3350);
DISPLAY 0.489362 (4600 3350);
PAINT SKYBLUE (4600 3350);
FORCEPROP 0 LAST $SEC 1
J 0
(4600 3400);
DISPLAY 0.680851 (4600 3400);
PAINT MONO (4600 3400);
DISPLAY INVISIBLE (4600 3400);
FORCEPROP 0 LAST CDS_SEC 1
J 0
(4600 3400);
DISPLAY 1.021277 (4600 3400);
DISPLAY INVISIBLE (4600 3400);
FORCEPROP 1 LASTPIN (4550 3300) $PN 1
J 0
(4560 3280);
DISPLAY 0.489362 (4560 3280);
PAINT MONO (4560 3280);
FORCEPROP 1 LASTPIN (4550 3100) $PN 2
J 0
(4560 3080);
DISPLAY 0.489362 (4560 3080);
PAINT MONO (4560 3080);
FORCEPROP 1 LAST MATERIAL X6S
J 0
(4600 3150);
DISPLAY 0.489362 (4600 3150);
PAINT SKYBLUE (4600 3150);
FORCEPROP 1 LAST TOLERANCE 10%
J 0
(4600 3200);
DISPLAY 0.489362 (4600 3200);
PAINT SKYBLUE (4600 3200);
FORCEPROP 1 LAST VALUE 10UF
J 0
(4600 3300);
DISPLAY 0.489362 (4600 3300);
PAINT SKYBLUE (4600 3300);
FORCEPROP 1 LAST PART_NUMBER CH6104KEA00
J 0
(4600 3050);
DISPLAY 0.489362 (4600 3050);
PAINT SKYBLUE (4600 3050);
FORCEPROP 1 LAST VOLTAGE 25V
J 0
(4600 3250);
DISPLAY 0.489362 (4600 3250);
PAINT SKYBLUE (4600 3250);
FORCEPROP 1 LAST PACK_TYPE C0805
J 0
(4600 3100);
DISPLAY 0.489362 (4600 3100);
PAINT SKYBLUE (4600 3100);
FORCEPROP 2 LAST CDS_LIB pure_quanta
J 0
(4550 3200);
DISPLAY INVISIBLE (4550 3200);
FORCEPROP 1 LAST PATH I41
J 0
(4600 3350);
DISPLAY 0.978723 (4600 3350);
PAINT WHITE (4600 3350);
DISPLAY INVISIBLE (4600 3350);
FORCEADD Q_CAP..1
(4950 3200);
FORCEPROP 1 LAST LOCATION PC157_2
J 0
(5000 3350);
DISPLAY 0.489362 (5000 3350);
PAINT SKYBLUE (5000 3350);
FORCEPROP 0 LAST $SEC 1
J 0
(5000 3400);
DISPLAY 0.680851 (5000 3400);
PAINT MONO (5000 3400);
DISPLAY INVISIBLE (5000 3400);
FORCEPROP 0 LAST CDS_SEC 1
J 0
(5000 3400);
DISPLAY 1.021277 (5000 3400);
DISPLAY INVISIBLE (5000 3400);
FORCEPROP 1 LASTPIN (4950 3300) $PN 1
J 0
(4960 3280);
DISPLAY 0.489362 (4960 3280);
PAINT MONO (4960 3280);
FORCEPROP 1 LASTPIN (4950 3100) $PN 2
J 0
(4960 3080);
DISPLAY 0.489362 (4960 3080);
PAINT MONO (4960 3080);
FORCEPROP 1 LAST MATERIAL X6S
J 0
(5000 3150);
DISPLAY 0.489362 (5000 3150);
PAINT SKYBLUE (5000 3150);
FORCEPROP 1 LAST TOLERANCE 10%
J 0
(5000 3200);
DISPLAY 0.489362 (5000 3200);
PAINT SKYBLUE (5000 3200);
FORCEPROP 1 LAST VALUE 10UF
J 0
(5000 3300);
DISPLAY 0.489362 (5000 3300);
PAINT SKYBLUE (5000 3300);
FORCEPROP 1 LAST PART_NUMBER CH6104KEA00
J 0
(5000 3050);
DISPLAY 0.489362 (5000 3050);
PAINT SKYBLUE (5000 3050);
FORCEPROP 1 LAST VOLTAGE 25V
J 0
(5000 3250);
DISPLAY 0.489362 (5000 3250);
PAINT SKYBLUE (5000 3250);
FORCEPROP 1 LAST PACK_TYPE C0805
J 0
(5000 3100);
DISPLAY 0.489362 (5000 3100);
PAINT SKYBLUE (5000 3100);
FORCEPROP 2 LAST CDS_LIB pure_quanta
J 0
(4950 3200);
DISPLAY INVISIBLE (4950 3200);
FORCEPROP 1 LAST PATH I42
J 0
(5000 3350);
DISPLAY 0.978723 (5000 3350);
PAINT WHITE (5000 3350);
DISPLAY INVISIBLE (5000 3350);
FORCEADD UNIVERSAL_GND..1
(5425 2850);
FORCEPROP 3 LASTPIN (5425 2900) SIG_NAME GND\g
J 0
(5435 2910);
DISPLAY 0.659574 (5435 2910);
PAINT MONO (5435 2910);
DISPLAY INVISIBLE (5435 2910);
FORCEPROP 2 LAST CDS_LIB pure_quanta_power
J 0
(5425 2850);
PAINT MONO (5425 2850);
DISPLAY INVISIBLE (5425 2850);
FORCEPROP 1 LAST PATH I44
J 0
(5500 2850);
DISPLAY 0.872340 (5500 2850);
PAINT AQUA (5500 2850);
DISPLAY INVISIBLE (5500 2850);
FORCEPROP 1 LAST HDL_POWER GND
J 1
(5450 2775);
DISPLAY 0.872340 (5450 2775);
PAINT GREEN (5450 2775);
DISPLAY INVISIBLE (5450 2775);
FORCEADD Q_CAP..1
(4000 5975);
FORCEPROP 1 LAST LOCATION PC150_1
J 0
(4050 6125);
DISPLAY 0.489362 (4050 6125);
PAINT SKYBLUE (4050 6125);
FORCEPROP 0 LAST $SEC 1
J 0
(4050 6175);
DISPLAY 0.680851 (4050 6175);
PAINT MONO (4050 6175);
DISPLAY INVISIBLE (4050 6175);
FORCEPROP 0 LAST CDS_SEC 1
J 0
(4050 6175);
DISPLAY 1.021277 (4050 6175);
DISPLAY INVISIBLE (4050 6175);
FORCEPROP 1 LASTPIN (4000 6075) $PN 1
J 0
(4010 6055);
DISPLAY 0.489362 (4010 6055);
PAINT MONO (4010 6055);
FORCEPROP 1 LASTPIN (4000 5875) $PN 2
J 0
(4010 5855);
DISPLAY 0.489362 (4010 5855);
PAINT MONO (4010 5855);
FORCEPROP 1 LAST PART_NUMBER CH5104KEB02
J 0
(4050 5825);
DISPLAY 0.489362 (4050 5825);
PAINT SKYBLUE (4050 5825);
FORCEPROP 1 LAST MATERIAL X6S
J 0
(4050 5925);
DISPLAY 0.489362 (4050 5925);
PAINT SKYBLUE (4050 5925);
FORCEPROP 1 LAST TOLERANCE 10%
J 0
(4050 5975);
DISPLAY 0.489362 (4050 5975);
PAINT SKYBLUE (4050 5975);
FORCEPROP 1 LAST VALUE 1UF
J 0
(4050 6075);
DISPLAY 0.489362 (4050 6075);
PAINT SKYBLUE (4050 6075);
FORCEPROP 1 LAST VOLTAGE 25V
J 0
(4050 6025);
DISPLAY 0.489362 (4050 6025);
PAINT SKYBLUE (4050 6025);
FORCEPROP 1 LAST PACK_TYPE C0402
J 0
(4050 5875);
DISPLAY 0.489362 (4050 5875);
PAINT SKYBLUE (4050 5875);
FORCEPROP 2 LAST CDS_LIB pure_quanta
J 0
(4000 5975);
DISPLAY INVISIBLE (4000 5975);
FORCEPROP 1 LAST PATH I50
J 0
(4050 6125);
DISPLAY 0.978723 (4050 6125);
PAINT WHITE (4050 6125);
DISPLAY INVISIBLE (4050 6125);
FORCEADD Q_RES..1
(3925 5425);
FORCEPROP 1 LAST LOCATION PR101
J 0
(3900 5475);
DISPLAY 0.489362 (3900 5475);
PAINT SKYBLUE (3900 5475);
FORCEPROP 2 LAST $SEC 1
J 0
(3875 5625);
DISPLAY 0.680851 (3875 5625);
PAINT MONO (3875 5625);
DISPLAY INVISIBLE (3875 5625);
FORCEPROP 2 LAST CDS_SEC 1
J 0
(3875 5625);
DISPLAY 1.021277 (3875 5625);
DISPLAY INVISIBLE (3875 5625);
FORCEPROP 1 LASTPIN (3825 5425) $PN 1
J 0
(3837 5437);
DISPLAY 0.489362 (3837 5437);
FORCEPROP 1 LASTPIN (4025 5425) $PN 2
J 0
(3987 5437);
DISPLAY 0.489362 (3987 5437);
FORCEPROP 1 LAST PACK_TYPE 0402LF
J 0
(4000 5375);
DISPLAY 0.489362 (4000 5375);
PAINT SKYBLUE (4000 5375);
FORCEPROP 1 LAST TOLERANCE 1%
J 0
(3800 5500);
DISPLAY 0.489362 (3800 5500);
PAINT SKYBLUE (3800 5500);
FORCEPROP 1 LAST MATERIAL CHIP
J 0
(4000 5325);
DISPLAY 0.489362 (4000 5325);
PAINT SKYBLUE (4000 5325);
FORCEPROP 1 LAST WATTAGE 1/16W
J 2
(4125 5500);
DISPLAY 0.489362 (4125 5500);
PAINT SKYBLUE (4125 5500);
FORCEPROP 1 LAST VALUE 4.7
J 2
(3775 5500);
DISPLAY 0.489362 (3775 5500);
PAINT SKYBLUE (3775 5500);
FORCEPROP 1 LAST PART_NUMBER CS-4702FB19
J 0
(3625 5375);
DISPLAY 0.489362 (3625 5375);
PAINT SKYBLUE (3625 5375);
FORCEPROP 1 LAST PATH I51
J 0
(3875 5575);
DISPLAY 0.978723 (3875 5575);
PAINT WHITE (3875 5575);
DISPLAY INVISIBLE (3875 5575);
FORCEPROP 2 LAST CDS_LIB pure_quanta
J 0
(3925 5425);
PAINT MONO (3925 5425);
DISPLAY INVISIBLE (3925 5425);
FORCEADD Q_CAP..1
(4400 5975);
FORCEPROP 1 LAST LOCATION PC152_1
J 0
(4450 6125);
DISPLAY 0.489362 (4450 6125);
PAINT SKYBLUE (4450 6125);
FORCEPROP 0 LAST $SEC 1
J 0
(4450 6175);
DISPLAY 0.680851 (4450 6175);
PAINT MONO (4450 6175);
DISPLAY INVISIBLE (4450 6175);
FORCEPROP 0 LAST CDS_SEC 1
J 0
(4450 6175);
DISPLAY 1.021277 (4450 6175);
DISPLAY INVISIBLE (4450 6175);
FORCEPROP 1 LASTPIN (4400 6075) $PN 1
J 0
(4410 6055);
DISPLAY 0.489362 (4410 6055);
PAINT MONO (4410 6055);
FORCEPROP 1 LASTPIN (4400 5875) $PN 2
J 0
(4410 5855);
DISPLAY 0.489362 (4410 5855);
PAINT MONO (4410 5855);
FORCEPROP 1 LAST PART_NUMBER CH6104KEA00
J 0
(4450 5825);
DISPLAY 0.489362 (4450 5825);
PAINT SKYBLUE (4450 5825);
FORCEPROP 1 LAST MATERIAL X6S
J 0
(4450 5925);
DISPLAY 0.489362 (4450 5925);
PAINT SKYBLUE (4450 5925);
FORCEPROP 1 LAST TOLERANCE 10%
J 0
(4450 5975);
DISPLAY 0.489362 (4450 5975);
PAINT SKYBLUE (4450 5975);
FORCEPROP 1 LAST VALUE 10UF
J 0
(4450 6075);
DISPLAY 0.489362 (4450 6075);
PAINT SKYBLUE (4450 6075);
FORCEPROP 1 LAST VOLTAGE 25V
J 0
(4450 6025);
DISPLAY 0.489362 (4450 6025);
PAINT SKYBLUE (4450 6025);
FORCEPROP 1 LAST PACK_TYPE C0805
J 0
(4450 5875);
DISPLAY 0.489362 (4450 5875);
PAINT SKYBLUE (4450 5875);
FORCEPROP 2 LAST CDS_LIB pure_quanta
J 0
(4400 5975);
DISPLAY INVISIBLE (4400 5975);
FORCEPROP 1 LAST PATH I52
J 0
(4450 6125);
DISPLAY 0.978723 (4450 6125);
PAINT WHITE (4450 6125);
DISPLAY INVISIBLE (4450 6125);
FORCEADD Q_CAP..1
(4800 5975);
FORCEPROP 1 LAST LOCATION PC154_1
J 0
(4850 6125);
DISPLAY 0.489362 (4850 6125);
PAINT SKYBLUE (4850 6125);
FORCEPROP 0 LAST $SEC 1
J 0
(4850 6175);
DISPLAY 0.680851 (4850 6175);
PAINT MONO (4850 6175);
DISPLAY INVISIBLE (4850 6175);
FORCEPROP 0 LAST CDS_SEC 1
J 0
(4850 6175);
DISPLAY 1.021277 (4850 6175);
DISPLAY INVISIBLE (4850 6175);
FORCEPROP 1 LASTPIN (4800 6075) $PN 1
J 0
(4810 6055);
DISPLAY 0.489362 (4810 6055);
PAINT MONO (4810 6055);
FORCEPROP 1 LASTPIN (4800 5875) $PN 2
J 0
(4810 5855);
DISPLAY 0.489362 (4810 5855);
PAINT MONO (4810 5855);
FORCEPROP 1 LAST MATERIAL X6S
J 0
(4850 5925);
DISPLAY 0.489362 (4850 5925);
PAINT SKYBLUE (4850 5925);
FORCEPROP 1 LAST PART_NUMBER CH6104KEA00
J 0
(4850 5825);
DISPLAY 0.489362 (4850 5825);
PAINT SKYBLUE (4850 5825);
FORCEPROP 1 LAST TOLERANCE 10%
J 0
(4850 5975);
DISPLAY 0.489362 (4850 5975);
PAINT SKYBLUE (4850 5975);
FORCEPROP 1 LAST VALUE 10UF
J 0
(4850 6075);
DISPLAY 0.489362 (4850 6075);
PAINT SKYBLUE (4850 6075);
FORCEPROP 1 LAST VOLTAGE 25V
J 0
(4850 6025);
DISPLAY 0.489362 (4850 6025);
PAINT SKYBLUE (4850 6025);
FORCEPROP 1 LAST PACK_TYPE C0805
J 0
(4850 5875);
DISPLAY 0.489362 (4850 5875);
PAINT SKYBLUE (4850 5875);
FORCEPROP 2 LAST CDS_LIB pure_quanta
J 0
(4800 5975);
DISPLAY INVISIBLE (4800 5975);
FORCEPROP 1 LAST PATH I56
J 0
(4850 6125);
DISPLAY 0.978723 (4850 6125);
PAINT WHITE (4850 6125);
DISPLAY INVISIBLE (4850 6125);
FORCEADD UNIVERSAL_GND..1
(5425 5625);
FORCEPROP 3 LASTPIN (5425 5675) SIG_NAME GND\g
J 0
(5435 5685);
DISPLAY 0.659574 (5435 5685);
PAINT MONO (5435 5685);
DISPLAY INVISIBLE (5435 5685);
FORCEPROP 2 LAST CDS_LIB pure_quanta_power
J 0
(5425 5625);
PAINT MONO (5425 5625);
DISPLAY INVISIBLE (5425 5625);
FORCEPROP 1 LAST PATH I57
J 0
(5500 5625);
DISPLAY 0.872340 (5500 5625);
PAINT AQUA (5500 5625);
DISPLAY INVISIBLE (5500 5625);
FORCEPROP 1 LAST HDL_POWER GND
J 1
(5450 5550);
DISPLAY 0.872340 (5450 5550);
PAINT GREEN (5450 5550);
DISPLAY INVISIBLE (5450 5550);
FORCEADD OFFPAGE..5
(1275 2275);
FORCEPROP 2 LAST $XR0 176 
J 0
(990 2275);
DISPLAY 0.638298 (990 2275);
PAINT MONO (990 2275);
FORCEPROP 2 LAST CDS_LIB standard
J 0
(1275 2275);
DISPLAY INVISIBLE (1275 2275);
FORCEPROP 1 LAST OFFPAGE TRUE
J 0
(1600 2150);
DISPLAY 0.872340 (1600 2150);
PAINT GREEN (1600 2150);
DISPLAY INVISIBLE (1600 2150);
FORCEPROP 1 LAST COMMENT_BODY TRUE
J 0
(1375 2200);
DISPLAY 0.872340 (1375 2200);
PAINT GREEN (1375 2200);
DISPLAY INVISIBLE (1375 2200);
FORCEPROP 2 LAST PATH I6
J 0
(1025 2325);
DISPLAY 1.021277 (1025 2325);
DISPLAY INVISIBLE (1025 2325);
FORCEADD Q_CAP..1
(7625 2075);
FORCEPROP 1 LAST LOCATION PC168_2
J 0
(7675 2200);
DISPLAY 0.489362 (7675 2200);
PAINT SKYBLUE (7675 2200);
FORCEPROP 0 LAST $SEC 1
J 0
(7675 2250);
DISPLAY 0.680851 (7675 2250);
PAINT MONO (7675 2250);
DISPLAY INVISIBLE (7675 2250);
FORCEPROP 0 LAST CDS_SEC 1
J 0
(7675 2250);
DISPLAY 1.021277 (7675 2250);
DISPLAY INVISIBLE (7675 2250);
FORCEPROP 1 LASTPIN (7625 2175) $PN 1
J 0
(7635 2155);
DISPLAY 0.489362 (7635 2155);
PAINT MONO (7635 2155);
FORCEPROP 1 LASTPIN (7625 1975) $PN 2
J 0
(7635 1955);
DISPLAY 0.489362 (7635 1955);
PAINT MONO (7635 1955);
FORCEPROP 1 LAST MATERIAL X6S
J 0
(7675 2000);
DISPLAY 0.489362 (7675 2000);
PAINT SKYBLUE (7675 2000);
FORCEPROP 1 LAST TOLERANCE 20%
J 0
(7675 2050);
DISPLAY 0.489362 (7675 2050);
PAINT SKYBLUE (7675 2050);
FORCEPROP 1 LAST VALUE 22UF
J 0
(7675 2150);
DISPLAY 0.489362 (7675 2150);
PAINT SKYBLUE (7675 2150);
FORCEPROP 1 LAST PART_NUMBER TMP_QCH622KMEA01
J 0
(7675 1900);
DISPLAY 0.489362 (7675 1900);
PAINT SKYBLUE (7675 1900);
FORCEPROP 1 LAST VOLTAGE 4V
J 0
(7675 2100);
DISPLAY 0.489362 (7675 2100);
PAINT SKYBLUE (7675 2100);
FORCEPROP 1 LAST PACK_TYPE 0805
J 0
(7675 1950);
DISPLAY 0.489362 (7675 1950);
PAINT SKYBLUE (7675 1950);
FORCEPROP 2 LAST CDS_LIB pure_quanta
J 0
(7625 2075);
DISPLAY INVISIBLE (7625 2075);
FORCEPROP 1 LAST PATH I60
J 0
(7675 2225);
DISPLAY 0.978723 (7675 2225);
PAINT WHITE (7675 2225);
DISPLAY INVISIBLE (7675 2225);
FORCEADD Q_CAP..1
(8050 2075);
FORCEPROP 1 LAST LOCATION PC170_2
J 0
(8100 2200);
DISPLAY 0.489362 (8100 2200);
PAINT SKYBLUE (8100 2200);
FORCEPROP 0 LAST $SEC 1
J 0
(8100 2250);
DISPLAY 0.680851 (8100 2250);
PAINT MONO (8100 2250);
DISPLAY INVISIBLE (8100 2250);
FORCEPROP 0 LAST CDS_SEC 1
J 0
(8100 2250);
DISPLAY 1.021277 (8100 2250);
DISPLAY INVISIBLE (8100 2250);
FORCEPROP 1 LASTPIN (8050 2175) $PN 1
J 0
(8060 2155);
DISPLAY 0.489362 (8060 2155);
PAINT MONO (8060 2155);
FORCEPROP 1 LASTPIN (8050 1975) $PN 2
J 0
(8060 1955);
DISPLAY 0.489362 (8060 1955);
PAINT MONO (8060 1955);
FORCEPROP 1 LAST MATERIAL X6S
J 0
(8100 2000);
DISPLAY 0.489362 (8100 2000);
PAINT SKYBLUE (8100 2000);
FORCEPROP 1 LAST TOLERANCE 20%
J 0
(8100 2050);
DISPLAY 0.489362 (8100 2050);
PAINT SKYBLUE (8100 2050);
FORCEPROP 1 LAST VALUE 22UF
J 0
(8100 2150);
DISPLAY 0.489362 (8100 2150);
PAINT SKYBLUE (8100 2150);
FORCEPROP 1 LAST PART_NUMBER TMP_QCH622KMEA01
J 0
(8100 1900);
DISPLAY 0.489362 (8100 1900);
PAINT SKYBLUE (8100 1900);
FORCEPROP 1 LAST VOLTAGE 4V
J 0
(8100 2100);
DISPLAY 0.489362 (8100 2100);
PAINT SKYBLUE (8100 2100);
FORCEPROP 1 LAST PACK_TYPE 0805
J 0
(8100 1950);
DISPLAY 0.489362 (8100 1950);
PAINT SKYBLUE (8100 1950);
FORCEPROP 2 LAST CDS_LIB pure_quanta
J 0
(8050 2075);
DISPLAY INVISIBLE (8050 2075);
FORCEPROP 1 LAST PATH I61
J 0
(8100 2225);
DISPLAY 0.978723 (8100 2225);
PAINT WHITE (8100 2225);
DISPLAY INVISIBLE (8100 2225);
FORCEADD VCC_CORE..1
(8050 2425);
FORCEPROP 3 LASTPIN (8050 2375) SIG_NAME PVDDIO_P0\g
J 0
(8060 2385);
DISPLAY 0.659574 (8060 2385);
PAINT MONO (8060 2385);
DISPLAY INVISIBLE (8060 2385);
FORCEPROP 1 LAST HDL_POWER PVDDIO_P0
J 1
(8050 2475);
DISPLAY 0.489362 (8050 2475);
PAINT GREEN (8050 2475);
FORCEPROP 2 LAST CDS_LIB pure_quanta_power
J 0
(8050 2425);
DISPLAY INVISIBLE (8050 2425);
FORCEPROP 1 LAST PATH I64
J 0
(8100 2450);
DISPLAY 0.872340 (8100 2450);
PAINT AQUA (8100 2450);
DISPLAY INVISIBLE (8100 2450);
FORCEADD Q_CAPP..1
(7525 3275);
FORCEPROP 1 LAST LOCATION PC162
J 0
(7575 3425);
DISPLAY 0.489362 (7575 3425);
PAINT SKYBLUE (7575 3425);
FORCEPROP 0 LAST $SEC 1
J 0
(7575 3475);
DISPLAY 0.680851 (7575 3475);
PAINT MONO (7575 3475);
DISPLAY INVISIBLE (7575 3475);
FORCEPROP 0 LAST CDS_SEC 1
J 0
(7575 3475);
DISPLAY 1.021277 (7575 3475);
DISPLAY INVISIBLE (7575 3475);
FORCEPROP 1 LASTPIN (7525 3375) $PN 1
J 0
(7535 3360);
DISPLAY 0.489362 (7535 3360);
PAINT MONO (7535 3360);
FORCEPROP 1 LASTPIN (7525 3175) $PN 2
J 0
(7535 3160);
DISPLAY 0.489362 (7535 3160);
PAINT MONO (7535 3160);
FORCEPROP 1 LAST PART_NUMBER CH747LM8825
J 0
(7575 3125);
DISPLAY 0.489362 (7575 3125);
PAINT SKYBLUE (7575 3125);
FORCEPROP 1 LAST MATERIAL SPCAP
J 0
(7575 3225);
DISPLAY 0.489362 (7575 3225);
PAINT SKYBLUE (7575 3225);
FORCEPROP 1 LAST TOLERANCE 20%
J 0
(7575 3325);
DISPLAY 0.489362 (7575 3325);
PAINT SKYBLUE (7575 3325);
FORCEPROP 1 LAST VALUE 470UF
J 0
(7575 3375);
DISPLAY 0.489362 (7575 3375);
PAINT SKYBLUE (7575 3375);
FORCEPROP 1 LAST VOLTAGE 2.5V
J 0
(7575 3275);
DISPLAY 0.489362 (7575 3275);
PAINT SKYBLUE (7575 3275);
FORCEPROP 1 LAST PACK_TYPE SMLF
J 0
(7575 3175);
DISPLAY 0.489362 (7575 3175);
PAINT SKYBLUE (7575 3175);
FORCEPROP 2 LAST CDS_LIB pure_quanta
J 0
(7525 3275);
DISPLAY INVISIBLE (7525 3275);
FORCEPROP 1 LAST PATH I66
J 0
(7575 3425);
DISPLAY 0.978723 (7575 3425);
DISPLAY INVISIBLE (7575 3425);
FORCEADD UNIVERSAL_GND..1
(7925 2925);
FORCEPROP 3 LASTPIN (7925 2975) SIG_NAME GND\g
J 0
(7935 2985);
DISPLAY 0.659574 (7935 2985);
PAINT MONO (7935 2985);
DISPLAY INVISIBLE (7935 2985);
FORCEPROP 2 LAST CDS_LIB pure_quanta_power
J 0
(7925 2925);
PAINT MONO (7925 2925);
DISPLAY INVISIBLE (7925 2925);
FORCEPROP 1 LAST PATH I67
J 0
(8000 2925);
DISPLAY 0.872340 (8000 2925);
PAINT AQUA (8000 2925);
DISPLAY INVISIBLE (8000 2925);
FORCEPROP 1 LAST HDL_POWER GND
J 1
(7950 2850);
DISPLAY 0.872340 (7950 2850);
PAINT GREEN (7950 2850);
DISPLAY INVISIBLE (7950 2850);
FORCEADD Q_CAPP..1
(7925 3275);
FORCEPROP 1 LAST LOCATION PC165
J 0
(8000 3425);
DISPLAY 0.489362 (8000 3425);
PAINT SKYBLUE (8000 3425);
FORCEPROP 2 LAST $SEC 1
J 0
(7975 3475);
DISPLAY 0.680851 (7975 3475);
PAINT MONO (7975 3475);
DISPLAY INVISIBLE (7975 3475);
FORCEPROP 2 LAST CDS_SEC 1
J 0
(7975 3475);
DISPLAY 1.021277 (7975 3475);
DISPLAY INVISIBLE (7975 3475);
FORCEPROP 1 LASTPIN (7925 3375) $PN 1
J 0
(7935 3360);
DISPLAY 0.489362 (7935 3360);
PAINT MONO (7935 3360);
FORCEPROP 1 LASTPIN (7925 3175) $PN 2
J 0
(7935 3160);
DISPLAY 0.489362 (7935 3160);
PAINT MONO (7935 3160);
FORCEPROP 1 LAST MATERIAL SPCAP
J 0
(8000 3225);
DISPLAY 0.489362 (8000 3225);
PAINT SKYBLUE (8000 3225);
FORCEPROP 1 LAST TOLERANCE 20%
J 0
(8000 3325);
DISPLAY 0.489362 (8000 3325);
PAINT SKYBLUE (8000 3325);
FORCEPROP 1 LAST VALUE 470UF
J 0
(8000 3375);
DISPLAY 0.489362 (8000 3375);
PAINT SKYBLUE (8000 3375);
FORCEPROP 1 LAST PART_NUMBER CH747LM8825
J 0
(8000 3125);
DISPLAY 0.489362 (8000 3125);
PAINT SKYBLUE (8000 3125);
FORCEPROP 1 LAST VOLTAGE 2.5V
J 0
(8000 3275);
DISPLAY 0.489362 (8000 3275);
PAINT SKYBLUE (8000 3275);
FORCEPROP 1 LAST PACK_TYPE SMLF
J 0
(8000 3175);
DISPLAY 0.489362 (8000 3175);
PAINT SKYBLUE (8000 3175);
FORCEPROP 2 LAST CDS_LIB pure_quanta
J 0
(7925 3275);
DISPLAY INVISIBLE (7925 3275);
FORCEPROP 1 LAST PATH I68
J 0
(7975 3425);
DISPLAY 0.978723 (7975 3425);
DISPLAY INVISIBLE (7975 3425);
FORCEADD VCC_CORE..1
(7925 3600);
FORCEPROP 3 LASTPIN (7925 3550) SIG_NAME PVDDIO_P0\g
J 0
(7935 3560);
DISPLAY 0.659574 (7935 3560);
PAINT MONO (7935 3560);
DISPLAY INVISIBLE (7935 3560);
FORCEPROP 1 LAST HDL_POWER PVDDIO_P0
J 1
(7925 3650);
DISPLAY 0.489362 (7925 3650);
PAINT GREEN (7925 3650);
FORCEPROP 2 LAST CDS_LIB pure_quanta_power
J 0
(7925 3600);
DISPLAY INVISIBLE (7925 3600);
FORCEPROP 1 LAST PATH I69
J 0
(7975 3625);
DISPLAY 0.872340 (7975 3625);
PAINT AQUA (7975 3625);
DISPLAY INVISIBLE (7975 3625);
FORCEADD OFFPAGE..1
(1275 2175);
FORCEPROP 2 LAST $XR5 182 
J 0
(423 2175);
DISPLAY 0.638298 (423 2175);
PAINT MONO (423 2175);
FORCEPROP 2 LAST $XR4 181 
J 0
(543 2175);
DISPLAY 0.638298 (543 2175);
PAINT MONO (543 2175);
FORCEPROP 2 LAST $XR3 179 
J 0
(663 2175);
DISPLAY 0.638298 (663 2175);
PAINT MONO (663 2175);
FORCEPROP 2 LAST $XR2 178 
J 0
(783 2175);
DISPLAY 0.638298 (783 2175);
PAINT MONO (783 2175);
FORCEPROP 2 LAST $XR1 177 
J 0
(903 2175);
DISPLAY 0.638298 (903 2175);
PAINT MONO (903 2175);
FORCEPROP 2 LAST $XR0 176 
J 0
(1023 2175);
DISPLAY 0.638298 (1023 2175);
PAINT MONO (1023 2175);
FORCEPROP 2 LAST CDS_LIB standard
J 0
(1275 2175);
DISPLAY INVISIBLE (1275 2175);
FORCEPROP 1 LAST OFFPAGE TRUE
J 0
(1600 2050);
DISPLAY 0.872340 (1600 2050);
PAINT GREEN (1600 2050);
DISPLAY INVISIBLE (1600 2050);
FORCEPROP 1 LAST COMMENT_BODY TRUE
J 0
(1400 2075);
DISPLAY 0.872340 (1400 2075);
PAINT GREEN (1400 2075);
DISPLAY INVISIBLE (1400 2075);
FORCEPROP 2 LAST PATH I7
J 0
(1000 2225);
DISPLAY 1.021277 (1000 2225);
DISPLAY INVISIBLE (1000 2225);
FORCEADD Q_CAP..1
(7175 4875);
FORCEPROP 1 LAST LOCATION PC107
J 0
(7225 5000);
DISPLAY 0.489362 (7225 5000);
PAINT SKYBLUE (7225 5000);
FORCEPROP 0 LAST $SEC 1
J 0
(7225 5050);
DISPLAY 0.680851 (7225 5050);
PAINT MONO (7225 5050);
DISPLAY INVISIBLE (7225 5050);
FORCEPROP 0 LAST CDS_SEC 1
J 0
(7225 5050);
DISPLAY 1.021277 (7225 5050);
DISPLAY INVISIBLE (7225 5050);
FORCEPROP 1 LASTPIN (7175 4975) $PN 1
J 0
(7185 4955);
DISPLAY 0.489362 (7185 4955);
PAINT MONO (7185 4955);
FORCEPROP 1 LASTPIN (7175 4775) $PN 2
J 0
(7185 4755);
DISPLAY 0.489362 (7185 4755);
PAINT MONO (7185 4755);
FORCEPROP 1 LAST MATERIAL X7R
J 0
(7225 4800);
DISPLAY 0.489362 (7225 4800);
PAINT SKYBLUE (7225 4800);
FORCEPROP 1 LAST TOLERANCE 10%
J 0
(7225 4850);
DISPLAY 0.489362 (7225 4850);
PAINT SKYBLUE (7225 4850);
FORCEPROP 1 LAST VALUE 0.1UF
J 0
(7225 4950);
DISPLAY 0.489362 (7225 4950);
PAINT SKYBLUE (7225 4950);
FORCEPROP 1 LAST PART_NUMBER CH4104K1B00
J 0
(7225 4700);
DISPLAY 0.489362 (7225 4700);
PAINT SKYBLUE (7225 4700);
FORCEPROP 1 LAST VOLTAGE 25V
J 0
(7225 4900);
DISPLAY 0.489362 (7225 4900);
PAINT SKYBLUE (7225 4900);
FORCEPROP 1 LAST PACK_TYPE 0402
J 0
(7225 4750);
DISPLAY 0.489362 (7225 4750);
PAINT SKYBLUE (7225 4750);
FORCEPROP 2 LAST CDS_LIB pure_quanta
J 0
(7175 4875);
DISPLAY INVISIBLE (7175 4875);
FORCEPROP 1 LAST PATH I70
J 0
(7225 5025);
DISPLAY 0.978723 (7225 5025);
PAINT WHITE (7225 5025);
DISPLAY INVISIBLE (7225 5025);
FORCEADD VCC_CORE..1
(6375 6350);
FORCEPROP 3 LASTPIN (6375 6300) SIG_NAME P12V_STBY\g
J 0
(6385 6310);
DISPLAY 0.659574 (6385 6310);
PAINT MONO (6385 6310);
DISPLAY INVISIBLE (6385 6310);
FORCEPROP 1 LAST HDL_POWER P12V_STBY
J 1
(6375 6400);
DISPLAY 0.489362 (6375 6400);
PAINT GREEN (6375 6400);
FORCEPROP 2 LAST CDS_LIB pure_quanta_power
J 0
(6375 6350);
DISPLAY INVISIBLE (6375 6350);
FORCEPROP 1 LAST PATH I71
J 0
(6425 6375);
DISPLAY 0.872340 (6425 6375);
PAINT AQUA (6425 6375);
DISPLAY INVISIBLE (6425 6375);
FORCEADD Q_CAP..1
(7675 4875);
FORCEPROP 1 LAST LOCATION PC166_1
J 0
(7725 5000);
DISPLAY 0.489362 (7725 5000);
PAINT SKYBLUE (7725 5000);
FORCEPROP 0 LAST $SEC 1
J 0
(7725 5050);
DISPLAY 0.680851 (7725 5050);
PAINT MONO (7725 5050);
DISPLAY INVISIBLE (7725 5050);
FORCEPROP 0 LAST CDS_SEC 1
J 0
(7725 5050);
DISPLAY 1.021277 (7725 5050);
DISPLAY INVISIBLE (7725 5050);
FORCEPROP 1 LASTPIN (7675 4975) $PN 1
J 0
(7685 4955);
DISPLAY 0.489362 (7685 4955);
PAINT MONO (7685 4955);
FORCEPROP 1 LASTPIN (7675 4775) $PN 2
J 0
(7685 4755);
DISPLAY 0.489362 (7685 4755);
PAINT MONO (7685 4755);
FORCEPROP 1 LAST MATERIAL X6S
J 0
(7725 4800);
DISPLAY 0.489362 (7725 4800);
PAINT SKYBLUE (7725 4800);
FORCEPROP 1 LAST TOLERANCE 20%
J 0
(7725 4850);
DISPLAY 0.489362 (7725 4850);
PAINT SKYBLUE (7725 4850);
FORCEPROP 1 LAST VALUE 22UF
J 0
(7725 4950);
DISPLAY 0.489362 (7725 4950);
PAINT SKYBLUE (7725 4950);
FORCEPROP 1 LAST PART_NUMBER TMP_QCH622KMEA01
J 0
(7725 4700);
DISPLAY 0.489362 (7725 4700);
PAINT SKYBLUE (7725 4700);
FORCEPROP 1 LAST VOLTAGE 4V
J 0
(7725 4900);
DISPLAY 0.489362 (7725 4900);
PAINT SKYBLUE (7725 4900);
FORCEPROP 1 LAST PACK_TYPE 0805
J 0
(7725 4750);
DISPLAY 0.489362 (7725 4750);
PAINT SKYBLUE (7725 4750);
FORCEPROP 2 LAST CDS_LIB pure_quanta
J 0
(7675 4875);
DISPLAY INVISIBLE (7675 4875);
FORCEPROP 1 LAST PATH I72
J 0
(7725 5025);
DISPLAY 0.978723 (7725 5025);
PAINT WHITE (7725 5025);
DISPLAY INVISIBLE (7725 5025);
FORCEADD Q_CAP..1
(8100 4875);
FORCEPROP 1 LAST LOCATION PC169_1
J 0
(8150 5000);
DISPLAY 0.489362 (8150 5000);
PAINT SKYBLUE (8150 5000);
FORCEPROP 0 LAST $SEC 1
J 0
(8150 5050);
DISPLAY 0.680851 (8150 5050);
PAINT MONO (8150 5050);
DISPLAY INVISIBLE (8150 5050);
FORCEPROP 0 LAST CDS_SEC 1
J 0
(8150 5050);
DISPLAY 1.021277 (8150 5050);
DISPLAY INVISIBLE (8150 5050);
FORCEPROP 1 LASTPIN (8100 4975) $PN 1
J 0
(8110 4955);
DISPLAY 0.489362 (8110 4955);
PAINT MONO (8110 4955);
FORCEPROP 1 LASTPIN (8100 4775) $PN 2
J 0
(8110 4755);
DISPLAY 0.489362 (8110 4755);
PAINT MONO (8110 4755);
FORCEPROP 1 LAST MATERIAL X6S
J 0
(8150 4800);
DISPLAY 0.489362 (8150 4800);
PAINT SKYBLUE (8150 4800);
FORCEPROP 1 LAST TOLERANCE 20%
J 0
(8150 4850);
DISPLAY 0.489362 (8150 4850);
PAINT SKYBLUE (8150 4850);
FORCEPROP 1 LAST VALUE 22UF
J 0
(8150 4950);
DISPLAY 0.489362 (8150 4950);
PAINT SKYBLUE (8150 4950);
FORCEPROP 1 LAST VOLTAGE 4V
J 0
(8150 4900);
DISPLAY 0.489362 (8150 4900);
PAINT SKYBLUE (8150 4900);
FORCEPROP 1 LAST PACK_TYPE 0805
J 0
(8150 4750);
DISPLAY 0.489362 (8150 4750);
PAINT SKYBLUE (8150 4750);
FORCEPROP 2 LAST CDS_LIB pure_quanta
J 0
(8100 4875);
DISPLAY INVISIBLE (8100 4875);
FORCEPROP 1 LAST PATH I73
J 0
(8150 5025);
DISPLAY 0.978723 (8150 5025);
PAINT WHITE (8150 5025);
DISPLAY INVISIBLE (8150 5025);
FORCEPROP 1 LAST PART_NUMBER TMP_QCH622KMEA01
J 0
(8125 4700);
DISPLAY 0.489362 (8125 4700);
PAINT SKYBLUE (8125 4700);
DISPLAY INVISIBLE (8125 4700);
FORCEADD Q_INDUCTOR..1
(6050 6250);
FORCEPROP 1 LAST LOCATION PL19
J 0
(6175 6275);
DISPLAY 0.489362 (6175 6275);
PAINT SKYBLUE (6175 6275);
FORCEPROP 2 LAST $SEC 1
J 0
(6125 6350);
DISPLAY 0.680851 (6125 6350);
PAINT MONO (6125 6350);
DISPLAY INVISIBLE (6125 6350);
FORCEPROP 2 LAST CDS_SEC 1
J 0
(6125 6350);
DISPLAY 1.021277 (6125 6350);
DISPLAY INVISIBLE (6125 6350);
FORCEPROP 2 LASTPIN (5950 6225) $PN 1
J 2
(5940 6235);
DISPLAY 0.489362 (5940 6235);
FORCEPROP 2 LASTPIN (6150 6225) $PN 2
J 0
(6160 6235);
DISPLAY 0.489362 (6160 6235);
FORCEPROP 1 LAST MATERIAL IND
J 0
(5950 6375);
DISPLAY 0.489362 (5950 6375);
PAINT SKYBLUE (5950 6375);
FORCEPROP 2 LAST VALUE 50NH/86A
J 0
(5950 6475);
DISPLAY 0.489362 (5950 6475);
PAINT SKYBLUE (5950 6475);
FORCEPROP 1 LAST PART_NUMBER CVA50^0MZ09
J 0
(5950 6325);
DISPLAY 0.489362 (5950 6325);
PAINT SKYBLUE (5950 6325);
FORCEPROP 2 LAST PACK_TYPE SMLF
J 0
(5950 6425);
DISPLAY 0.489362 (5950 6425);
PAINT SKYBLUE (5950 6425);
FORCEPROP 1 LAST NEEDS_NO_SIZE TRUE
J 0
(6050 6250);
DISPLAY 0.468085 (6050 6250);
PAINT GREEN (6050 6250);
DISPLAY INVISIBLE (6050 6250);
FORCEPROP 2 LAST CDS_LIB pure_quanta
J 0
(6050 6250);
PAINT MONO (6050 6250);
DISPLAY INVISIBLE (6050 6250);
FORCEPROP 1 LAST PATH I74
J 0
(6125 6305);
DISPLAY 0.723404 (6125 6305);
PAINT GREEN (6125 6305);
DISPLAY INVISIBLE (6125 6305);
FORCEADD UNIVERSAL_GND..1
(8400 4525);
FORCEPROP 3 LASTPIN (8400 4575) SIG_NAME GND\g
J 0
(8410 4585);
DISPLAY 0.659574 (8410 4585);
PAINT MONO (8410 4585);
DISPLAY INVISIBLE (8410 4585);
FORCEPROP 2 LAST CDS_LIB pure_quanta_power
J 0
(8400 4525);
PAINT MONO (8400 4525);
DISPLAY INVISIBLE (8400 4525);
FORCEPROP 1 LAST PATH I75
J 0
(8475 4525);
DISPLAY 0.872340 (8475 4525);
PAINT AQUA (8475 4525);
DISPLAY INVISIBLE (8475 4525);
FORCEPROP 1 LAST HDL_POWER GND
J 1
(8425 4450);
DISPLAY 0.872340 (8425 4450);
PAINT GREEN (8425 4450);
DISPLAY INVISIBLE (8425 4450);
FORCEADD VCC_CORE..1
(8400 5200);
FORCEPROP 3 LASTPIN (8400 5150) SIG_NAME PVDDIO_P0\g
J 0
(8410 5160);
DISPLAY 0.659574 (8410 5160);
PAINT MONO (8410 5160);
DISPLAY INVISIBLE (8410 5160);
FORCEPROP 1 LAST HDL_POWER PVDDIO_P0
J 1
(8400 5250);
DISPLAY 0.489362 (8400 5250);
PAINT GREEN (8400 5250);
FORCEPROP 2 LAST CDS_LIB pure_quanta_power
J 0
(8400 5200);
DISPLAY INVISIBLE (8400 5200);
FORCEPROP 1 LAST PATH I76
J 0
(8450 5225);
DISPLAY 0.872340 (8450 5225);
PAINT AQUA (8450 5225);
DISPLAY INVISIBLE (8450 5225);
FORCEADD UNIVERSAL_GND..1
(8050 1725);
FORCEPROP 3 LASTPIN (8050 1775) SIG_NAME GND\g
J 0
(8060 1785);
DISPLAY 0.659574 (8060 1785);
PAINT MONO (8060 1785);
DISPLAY INVISIBLE (8060 1785);
FORCEPROP 2 LAST CDS_LIB pure_quanta_power
J 0
(8050 1725);
PAINT MONO (8050 1725);
DISPLAY INVISIBLE (8050 1725);
FORCEPROP 1 LAST PATH I80
J 0
(8125 1725);
DISPLAY 0.872340 (8125 1725);
PAINT AQUA (8125 1725);
DISPLAY INVISIBLE (8125 1725);
FORCEPROP 1 LAST HDL_POWER GND
J 1
(8075 1650);
DISPLAY 0.872340 (8075 1650);
PAINT GREEN (8075 1650);
DISPLAY INVISIBLE (8075 1650);
FORCEADD Q_CAP..1
(5225 6000);
FORCEPROP 1 LAST LOCATION PC158_1
J 0
(5275 6100);
DISPLAY 0.489362 (5275 6100);
PAINT SKYBLUE (5275 6100);
FORCEPROP 0 LAST $SEC 1
J 0
(5275 6150);
DISPLAY 0.680851 (5275 6150);
PAINT MONO (5275 6150);
DISPLAY INVISIBLE (5275 6150);
FORCEPROP 0 LAST CDS_SEC 1
J 0
(5275 6150);
DISPLAY 1.021277 (5275 6150);
DISPLAY INVISIBLE (5275 6150);
FORCEPROP 1 LASTPIN (5225 6100) $PN 1
J 0
(5235 6080);
DISPLAY 0.489362 (5235 6080);
PAINT MONO (5235 6080);
FORCEPROP 1 LASTPIN (5225 5900) $PN 2
J 0
(5235 5880);
DISPLAY 0.489362 (5235 5880);
PAINT MONO (5235 5880);
FORCEPROP 1 LAST PACK_TYPE C0805
J 0
(5275 5800);
DISPLAY 0.489362 (5275 5800);
PAINT SKYBLUE (5275 5800);
FORCEPROP 1 LAST PART_NUMBER CH6104KEA00
J 0
(5275 5850);
DISPLAY 0.489362 (5275 5850);
PAINT SKYBLUE (5275 5850);
FORCEPROP 1 LAST MATERIAL X6S
J 0
(5275 5900);
DISPLAY 0.489362 (5275 5900);
PAINT SKYBLUE (5275 5900);
FORCEPROP 1 LAST TOLERANCE 10%
J 0
(5275 5950);
DISPLAY 0.489362 (5275 5950);
PAINT SKYBLUE (5275 5950);
FORCEPROP 1 LAST VALUE 10UF
J 0
(5275 6050);
DISPLAY 0.489362 (5275 6050);
PAINT SKYBLUE (5275 6050);
FORCEPROP 1 LAST VOLTAGE 25V
J 0
(5275 6000);
DISPLAY 0.489362 (5275 6000);
PAINT SKYBLUE (5275 6000);
FORCEPROP 2 LAST CDS_LIB pure_quanta
J 0
(5225 6000);
DISPLAY INVISIBLE (5225 6000);
FORCEPROP 1 LAST PATH I85
J 0
(5275 6150);
DISPLAY 0.978723 (5275 6150);
PAINT WHITE (5275 6150);
DISPLAY INVISIBLE (5275 6150);
FORCEADD Q_CAP..1
(5425 3200);
FORCEPROP 1 LAST LOCATION PC159_2
J 0
(5500 3350);
DISPLAY 0.489362 (5500 3350);
PAINT SKYBLUE (5500 3350);
FORCEPROP 0 LAST $SEC 1
J 0
(5475 3350);
DISPLAY 0.680851 (5475 3350);
PAINT MONO (5475 3350);
DISPLAY INVISIBLE (5475 3350);
FORCEPROP 0 LAST CDS_SEC 1
J 0
(5475 3350);
DISPLAY 1.021277 (5475 3350);
DISPLAY INVISIBLE (5475 3350);
FORCEPROP 1 LASTPIN (5425 3300) $PN 1
J 0
(5435 3280);
DISPLAY 0.489362 (5435 3280);
PAINT MONO (5435 3280);
FORCEPROP 1 LASTPIN (5425 3100) $PN 2
J 0
(5435 3080);
DISPLAY 0.489362 (5435 3080);
PAINT MONO (5435 3080);
FORCEPROP 1 LAST VALUE 10UF
J 0
(5500 3300);
DISPLAY 0.489362 (5500 3300);
PAINT SKYBLUE (5500 3300);
FORCEPROP 1 LAST MATERIAL X6S
J 0
(5500 3150);
DISPLAY 0.489362 (5500 3150);
PAINT SKYBLUE (5500 3150);
FORCEPROP 1 LAST TOLERANCE 10%
J 0
(5500 3200);
DISPLAY 0.489362 (5500 3200);
PAINT SKYBLUE (5500 3200);
FORCEPROP 1 LAST PART_NUMBER CH6104KEA00
J 0
(5500 3050);
DISPLAY 0.489362 (5500 3050);
PAINT SKYBLUE (5500 3050);
FORCEPROP 1 LAST VOLTAGE 25V
J 0
(5500 3250);
DISPLAY 0.489362 (5500 3250);
PAINT SKYBLUE (5500 3250);
FORCEPROP 1 LAST PACK_TYPE C0805
J 0
(5500 3100);
DISPLAY 0.489362 (5500 3100);
PAINT SKYBLUE (5500 3100);
FORCEPROP 2 LAST CDS_LIB pure_quanta
J 0
(5425 3200);
DISPLAY INVISIBLE (5425 3200);
FORCEPROP 1 LAST PATH I86
J 0
(5475 3350);
DISPLAY 0.978723 (5475 3350);
PAINT WHITE (5475 3350);
DISPLAY INVISIBLE (5475 3350);
FORCEADD OFFPAGE..6
(5150 2025);
FORCEPROP 2 LAST $XR0 182 
J 0
(4870 2025);
DISPLAY 0.638298 (4870 2025);
PAINT MONO (4870 2025);
FORCEPROP 2 LAST CDS_LIB standard
J 0
(5150 2025);
DISPLAY INVISIBLE (5150 2025);
FORCEPROP 1 LAST OFFPAGE TRUE
J 0
(5475 1900);
DISPLAY 0.872340 (5475 1900);
PAINT GREEN (5475 1900);
DISPLAY INVISIBLE (5475 1900);
FORCEPROP 1 LAST COMMENT_BODY TRUE
J 0
(5250 1950);
DISPLAY 0.872340 (5250 1950);
PAINT GREEN (5250 1950);
DISPLAY INVISIBLE (5250 1950);
FORCEPROP 2 LAST PATH I99
J 0
(5200 2100);
DISPLAY 1.021277 (5200 2100);
DISPLAY INVISIBLE (5200 2100);
FORCEADD DNS..1
(4275 4325);
PAINT RED (4275 4325);
FORCEPROP 2 LAST CDS_LIB mstr_misc
J 0
(4275 4325);
DISPLAY INVISIBLE (4275 4325);
FORCEPROP 1 LAST COMMENT_BODY TRUE
R 1
J 0
(4350 4100);
DISPLAY 0.872340 (4350 4100);
PAINT GREEN (4350 4100);
DISPLAY INVISIBLE (4350 4100);
FORCEADD DNS..1
(4275 1575);
PAINT RED (4275 1575);
FORCEPROP 2 LAST CDS_LIB mstr_misc
J 0
(4275 1575);
DISPLAY INVISIBLE (4275 1575);
FORCEPROP 1 LAST COMMENT_BODY TRUE
R 1
J 0
(4350 1350);
DISPLAY 0.872340 (4350 1350);
PAINT GREEN (4350 1350);
DISPLAY INVISIBLE (4350 1350);
FORCEADD DNS..1
(825 1750);
PAINT RED (825 1750);
FORCEPROP 2 LAST CDS_LIB mstr_misc
J 0
(825 1750);
PAINT MONO (825 1750);
DISPLAY INVISIBLE (825 1750);
FORCEPROP 1 LAST COMMENT_BODY TRUE
R 1
J 0
(900 1525);
DISPLAY 0.872340 (900 1525);
PAINT GREEN (900 1525);
DISPLAY INVISIBLE (900 1525);
FORCEADD DNS..1
(4275 2075);
PAINT RED (4275 2075);
FORCEPROP 2 LAST CDS_LIB mstr_misc
J 0
(4275 2075);
DISPLAY INVISIBLE (4275 2075);
FORCEPROP 1 LAST COMMENT_BODY TRUE
R 1
J 0
(4350 1850);
DISPLAY 0.872340 (4350 1850);
PAINT GREEN (4350 1850);
DISPLAY INVISIBLE (4350 1850);
FORCEADD DNS..1
(7125 3250);
PAINT RED (7125 3250);
FORCEPROP 2 LAST CDS_LIB mstr_misc
J 0
(7125 3250);
DISPLAY INVISIBLE (7125 3250);
FORCEPROP 1 LAST COMMENT_BODY TRUE
R 1
J 0
(7200 3025);
DISPLAY 0.872340 (7200 3025);
PAINT GREEN (7200 3025);
DISPLAY INVISIBLE (7200 3025);
FORCEADD DNS..1
(4275 4875);
PAINT RED (4275 4875);
FORCEPROP 2 LAST CDS_LIB mstr_misc
J 0
(4275 4875);
DISPLAY INVISIBLE (4275 4875);
FORCEPROP 1 LAST COMMENT_BODY TRUE
R 1
J 0
(4350 4650);
DISPLAY 0.872340 (4350 4650);
PAINT GREEN (4350 4650);
DISPLAY INVISIBLE (4350 4650);
FORCEADD QUANTA_TITLE_BLOCK_C..1
(8900 -75);
FORCEPROP 0 LAST CDS_CON_LAST_MODIFIED Fri Mar 11 14:53:29 2022
J 0
(7015 -60);
DISPLAY INVISIBLE (7015 -60);
FORCEPROP 1 LAST CUSTOM_TXT_CDS <CON_LAST_MODIFIED>
J 0
(7015 -60);
DISPLAY 0.978723 (7015 -60);
FORCEPROP 2 LAST CUSTOM_TXT_CDS <XR_PAGE_TITLE>
J 0
(1010 5175);
DISPLAY 0.638298 (1010 5175);
PAINT PINK (1010 5175);
DISPLAY INVISIBLE (1010 5175);
FORCEPROP 1 LAST CUSTOM_TXT_CDS <NAME_2>
J 0
(5725 -25);
FORCEPROP 1 LAST CUSTOM_TXT_CDS <NAME_1>
J 0
(5725 100);
FORCEPROP 1 LAST CUSTOM_TXT_CDS <Q_NUMBER>
J 0
(7497 28);
DISPLAY 1.212766 (7497 28);
FORCEPROP 1 LAST CUSTOM_TXT_CDS <Q_PROJ>
J 0
(6518 27);
DISPLAY 1.212766 (6518 27);
FORCEPROP 1 LAST CUSTOM_TXT_CDS <Q_REV>
J 0
(8716 28);
DISPLAY 1.212766 (8716 28);
FORCEPROP 1 LAST CUSTOM_TXT_CDS <CON_PAGE_NUM> OF <CON_TOTAL_PAGES>
J 0
(8454 -57);
DISPLAY 0.978723 (8454 -57);
FORCEPROP 1 LAST Q_TITLE PVDDIO_P0_VR PHASE 1&2
J 0
(-400 -25);
DISPLAY 2.446809 (-400 -25);
PAINT GREEN (-400 -25);
FORCEPROP 1 LAST Q_DEPT BU9
J 1
(5137 -26);
DISPLAY 1.957447 (5137 -26);
PAINT GREEN (5137 -26);
FORCEPROP 2 LAST CDS_LIB pure_quanta
J 0
(8900 -75);
DISPLAY INVISIBLE (8900 -75);
FORCEPROP 1 LAST CDS_LMAN_SYM_OUTLINE -9475,6775,100,-125
J 0
(8900 -75);
DISPLAY 0.468085 (8900 -75);
PAINT GREEN (8900 -75);
DISPLAY INVISIBLE (8900 -75);
FORCEPROP 2 LAST PAGE_BORDER TRUE
J 0
(1010 5175);
DISPLAY 0.638298 (1010 5175);
PAINT PINK (1010 5175);
DISPLAY INVISIBLE (1010 5175);
FORCEPROP 1 LAST COMMENT_BODY TRUE
J 0
(8912 -88);
DISPLAY 0.978723 (8912 -88);
PAINT GREEN (8912 -88);
DISPLAY INVISIBLE (8912 -88);
FORCEPROP 2 LAST CDS_XR_PAGE_TITLE CR-181 : @T6G_MB_LIB.T6G(SCH_1):PAGE181
J 0
(1010 5175);
DISPLAY 0.638298 (1010 5175);
PAINT PINK (1010 5175);
DISPLAY INVISIBLE (1010 5175);
FORCEADD DNS..1
(850 4600);
PAINT RED (850 4600);
FORCEPROP 2 LAST CDS_LIB mstr_misc
J 0
(850 4600);
PAINT MONO (850 4600);
DISPLAY INVISIBLE (850 4600);
FORCEPROP 1 LAST COMMENT_BODY TRUE
R 1
J 0
(925 4375);
DISPLAY 0.872340 (925 4375);
PAINT GREEN (925 4375);
DISPLAY INVISIBLE (925 4375);
WIRE 16 -1 (825 1675)(825 1600);
WIRE 16 -1 (1250 5250)(1250 5200);
WIRE 16 -1 (1600 5825)(1600 5700);
WIRE 16 -1 (1150 2575)(1150 2525);
WIRE 16 -1 (1500 3150)(1500 3025);
WIRE 16 -1 (850 4525)(850 4450);
WIRE 16 -1 (225 4500)(225 4600);
WIRE 16 -1 (250 1750)(250 1800);
WIRE 16 -1 (4300 4225)(4300 4150);
WIRE 16 -1 (4300 1475)(4300 1400);
WIRE 16 -1 (2225 4900)(225 4900);
WIRE 16 -1 (2225 4975)(2225 4900);
FORCEPROP 0 LAST CDS_PHYS_NET_NAME PVCCIN_CPU0_VREF
J 0
(2225 4925);
PAINT MONO (2225 4925);
DISPLAY INVISIBLE (2225 4925);
WIRE 16 -1 (225 4900)(225 4800);
WIRE 16 -1 (1350 4975)(2225 4975);
FORCEPROP 2 LAST SIG_NAME PVDDCR_CPU1_P0_VCCS
J 0
(1540 4985);
DISPLAY 0.489362 (1540 4985);
WIRE 16 -1 (2225 4975)(2375 4975);
WIRE 16 -1 (2375 1675)(1325 1675);
FORCEPROP 2 LAST SIG_NAME PVDDIO_P0_PWM2
J 0
(1390 1685);
DISPLAY 0.489362 (1390 1685);
WIRE 16 -1 (2375 1775)(1325 1775);
FORCEPROP 2 LAST SIG_NAME PVDDIO_P0_TEMP1
J 0
(1390 1785);
DISPLAY 0.489362 (1390 1785);
WIRE 16 -1 (825 1975)(2375 1975);
FORCEPROP 2 LAST SIG_NAME PVDDIO_P0_LSET2
J 0
(1415 1985);
DISPLAY 0.489362 (1415 1985);
FORCEPROP 2 LASTPROP $XRERR UNIQUE?
J 0
(1175 1985);
DISPLAY 0.638298 (1175 1985);
PAINT MONO (1175 1985);
DISPLAY INVISIBLE (1175 1985);
WIRE 16 -1 (825 1975)(825 1875);
WIRE 16 -1 (2225 2100)(250 2100);
WIRE 16 -1 (2225 2175)(2225 2100);
FORCEPROP 0 LAST CDS_PHYS_NET_NAME PVCCIN_CPU0_VREF
J 0
(2225 2125);
PAINT MONO (2225 2125);
DISPLAY INVISIBLE (2225 2125);
WIRE 16 -1 (250 2100)(250 2000);
WIRE 16 -1 (1325 2175)(2225 2175);
FORCEPROP 2 LAST SIG_NAME PVDDCR_CPU1_P0_VCCS
J 0
(1390 2185);
DISPLAY 0.489362 (1390 2185);
WIRE 16 -1 (2225 2175)(2375 2175);
WIRE 16 -1 (2375 2275)(1325 2275);
FORCEPROP 2 LAST SIG_NAME PVDDIO_P0_IMON2
J 0
(1390 2285);
DISPLAY 0.489362 (1390 2285);
WIRE 16 -1 (1150 3125)(1150 2850);
WIRE 16 -1 (1150 2850)(1550 2850);
WIRE 16 -1 (1150 2850)(1150 2775);
WIRE 16 -1 (1550 2850)(1550 2625);
WIRE 16 -1 (2225 2625)(1550 2625);
FORCEPROP 0 LAST CDS_PHYS_NET_NAME PVCCFA_EHV_FIVRA_CPU0_VDD2
J 0
(1615 2665);
PAINT MONO (1615 2665);
DISPLAY INVISIBLE (1615 2665);
FORCEPROP 2 LAST SIG_NAME PVDDIO_P0_VCC2
J 0
(1590 2635);
DISPLAY 0.489362 (1590 2635);
FORCEPROP 2 LASTPROP $XRERR UNIQUE?
J 0
(1350 2635);
DISPLAY 0.638298 (1350 2635);
PAINT MONO (1350 2635);
DISPLAY INVISIBLE (1350 2635);
WIRE 16 -1 (2375 2625)(2225 2625);
WIRE 16 -1 (2225 2625)(2225 2425);
WIRE 16 -1 (2375 2425)(2225 2425);
WIRE 16 -1 (1150 3325)(1150 3450);
WIRE 16 -1 (1150 3600)(1150 3450);
WIRE 16 -1 (1500 3450)(1150 3450);
WIRE 16 -1 (1825 3450)(1500 3450);
WIRE 16 -1 (1500 3350)(1500 3450);
WIRE 16 -1 (1825 2925)(1825 3450);
WIRE 16 -1 (1825 2925)(2375 2925);
WIRE 16 -1 (2375 4475)(1350 4475);
FORCEPROP 2 LAST SIG_NAME PVDDIO_P0_PWM1
J 0
(1415 4485);
DISPLAY 0.489362 (1415 4485);
WIRE 16 -1 (2375 4575)(1350 4575);
FORCEPROP 2 LAST SIG_NAME PVDDIO_P0_TEMP1
J 0
(1415 4585);
DISPLAY 0.489362 (1415 4585);
WIRE 16 -1 (850 4775)(2375 4775);
FORCEPROP 0 LAST CDS_PHYS_NET_NAME PVCCFA_EHV_FIVRA_CPU0_LSET1
J 0
(1440 4815);
PAINT MONO (1440 4815);
DISPLAY INVISIBLE (1440 4815);
FORCEPROP 2 LAST SIG_NAME PVDDIO_P0_LSET1
J 0
(1440 4785);
DISPLAY 0.489362 (1440 4785);
FORCEPROP 2 LASTPROP $XRERR UNIQUE?
J 0
(1200 4785);
DISPLAY 0.638298 (1200 4785);
PAINT MONO (1200 4785);
DISPLAY INVISIBLE (1200 4785);
WIRE 16 -1 (850 4775)(850 4725);
WIRE 16 -1 (1250 5525)(1825 5525);
WIRE 16 -1 (1250 5800)(1250 5525);
WIRE 16 -1 (1250 5525)(1250 5450);
WIRE 16 -1 (1825 5525)(1825 5425);
WIRE 16 -1 (2225 5425)(1825 5425);
FORCEPROP 0 LAST CDS_PHYS_NET_NAME PVCCFA_EHV_FIVRA_CPU0_VDD1
J 0
(1915 5465);
PAINT MONO (1915 5465);
DISPLAY INVISIBLE (1915 5465);
FORCEPROP 2 LAST SIG_NAME PVDDIO_P0_VCC1
J 0
(1890 5435);
DISPLAY 0.489362 (1890 5435);
FORCEPROP 2 LASTPROP $XRERR UNIQUE?
J 0
(1650 5435);
DISPLAY 0.638298 (1650 5435);
PAINT MONO (1650 5435);
DISPLAY INVISIBLE (1650 5435);
WIRE 16 -1 (2375 5425)(2225 5425);
WIRE 16 -1 (2225 5425)(2225 5225);
WIRE 16 -1 (2375 5225)(2225 5225);
WIRE 16 -1 (1925 5725)(2375 5725);
WIRE 16 -1 (1925 5725)(1925 6125);
WIRE 16 -1 (1925 6125)(1600 6125);
WIRE 16 -1 (1600 6025)(1600 6125);
WIRE 16 -1 (1600 6125)(1250 6125);
WIRE 16 -1 (1250 6275)(1250 6125);
WIRE 16 -1 (1250 6000)(1250 6125);
WIRE 16 -1 (3225 2375)(4825 2375);
FORCEPROP 2 LAST SIG_NAME SW_PVDDIO_P0_BOOTR2
J 0
(3415 2385);
DISPLAY 0.489362 (3415 2385);
FORCEPROP 2 LASTPROP $XRERR UNIQUE?
J 0
(3175 2385);
DISPLAY 0.638298 (3175 2385);
PAINT MONO (3175 2385);
DISPLAY INVISIBLE (3175 2385);
WIRE 16 -1 (4825 2375)(4825 2400);
WIRE 16 -1 (4300 2175)(4300 2275);
WIRE 16 -1 (4300 2275)(5800 2275);
WIRE 16 -1 (3225 2275)(4300 2275);
FORCEPROP 2 LAST SIG_NAME SW_PVDDIO_P0_SW2
J 0
(3415 2300);
DISPLAY 0.489362 (3415 2300);
FORCEPROP 2 LASTPROP $XRERR UNIQUE?
J 0
(3175 2300);
DISPLAY 0.638298 (3175 2300);
PAINT MONO (3175 2300);
DISPLAY INVISIBLE (3175 2300);
WIRE 16 -1 (6375 6300)(6375 6225);
WIRE 16 -1 (6375 6225)(6150 6225);
WIRE 16 -1 (7175 4775)(7175 4650);
WIRE 16 -1 (7675 4650)(7175 4650);
WIRE 16 -1 (8100 4650)(7675 4650);
WIRE 16 -1 (7675 4650)(7675 4775);
WIRE 16 -1 (8400 4650)(8100 4650);
WIRE 16 -1 (8100 4775)(8100 4650);
WIRE 16 -1 (8400 4775)(8400 4650);
WIRE 16 -1 (8400 4575)(8400 4650);
WIRE 16 -1 (6900 4750)(6900 4825);
WIRE 16 -1 (6425 4825)(6900 4825);
WIRE 16 -1 (5050 4825)(5625 4825);
FORCEPROP 2 LAST SIG_NAME IND_PVDDIO_P0_CPL2
J 0
(5115 4835);
DISPLAY 0.489362 (5115 4835);
WIRE 16 -1 (3225 5175)(4825 5175);
FORCEPROP 2 LAST SIG_NAME SW_PVDDIO_P0_BOOTR1
J 0
(3415 5185);
DISPLAY 0.489362 (3415 5185);
FORCEPROP 2 LASTPROP $XRERR UNIQUE?
J 0
(3175 5185);
DISPLAY 0.638298 (3175 5185);
PAINT MONO (3175 5185);
DISPLAY INVISIBLE (3175 5185);
WIRE 16 -1 (4825 5175)(4825 5200);
WIRE 16 -1 (7125 3375)(7125 3500);
WIRE 16 -1 (7125 3500)(7525 3500);
WIRE 16 -1 (7525 3500)(7925 3500);
WIRE 16 -1 (7525 3375)(7525 3500);
WIRE 16 -1 (7925 3550)(7925 3500);
WIRE 16 -1 (7925 3500)(7925 3375);
WIRE 16 -1 (8050 1850)(7625 1850);
WIRE 16 -1 (8050 1975)(8050 1850);
WIRE 16 -1 (8050 1775)(8050 1850);
WIRE 16 -1 (7625 1850)(7625 1975);
WIRE 16 -1 (6600 2025)(7000 2025);
FORCEPROP 2 LAST SIG_NAME IND_PVDDIO_P0_CPL2
J 0
(6615 2035);
DISPLAY 0.489362 (6615 2035);
WIRE 16 -1 (4200 2625)(4825 2625);
FORCEPROP 2 LAST SIG_NAME SW_PVDDIO_P0_BOOT2_R
J 0
(4415 2635);
DISPLAY 0.489362 (4415 2635);
FORCEPROP 2 LASTPROP $XRERR UNIQUE?
J 0
(4175 2635);
DISPLAY 0.638298 (4175 2635);
PAINT MONO (4175 2635);
DISPLAY INVISIBLE (4175 2635);
WIRE 16 -1 (4825 2625)(4825 2600);
WIRE 16 -1 (5200 2025)(5800 2025);
FORCEPROP 2 LAST SIG_NAME IND_PVDDIO_P0_CPL3
J 0
(5265 2035);
DISPLAY 0.489362 (5265 2035);
WIRE 16 -1 (3225 5425)(3825 5425);
FORCEPROP 2 LAST SIG_NAME SW_PVDDIO_P0_BOOT1
J 0
(3415 5435);
DISPLAY 0.489362 (3415 5435);
FORCEPROP 2 LASTPROP $XRERR UNIQUE?
J 0
(3175 5435);
DISPLAY 0.638298 (3175 5435);
PAINT MONO (3175 5435);
DISPLAY INVISIBLE (3175 5435);
WIRE 16 -1 (3800 4725)(3225 4725);
FORCEPROP 2 LAST SIG_NAME NC_PVDDIO_P0_GL2_1
J 0
(3340 4735);
DISPLAY 0.489362 (3340 4735);
FORCEPROP 2 LASTPROP $XRERR UNIQUE?
J 0
(3830 4725);
DISPLAY 0.638298 (3830 4725);
PAINT MONO (3830 4725);
DISPLAY INVISIBLE (3830 4725);
WIRE 16 -1 (3225 4775)(3800 4775);
FORCEPROP 2 LAST SIG_NAME NC_PVDDIO_P0_GL1_1
J 0
(3340 4785);
DISPLAY 0.489362 (3340 4785);
FORCEPROP 2 LASTPROP $XRERR UNIQUE?
J 0
(3830 4775);
DISPLAY 0.638298 (3830 4775);
PAINT MONO (3830 4775);
DISPLAY INVISIBLE (3830 4775);
WIRE 16 -1 (3475 4625)(3225 4625);
WIRE 16 -1 (3475 4575)(3475 4625);
WIRE 16 -1 (3225 4575)(3475 4575);
WIRE 16 -1 (3475 4575)(3475 4525);
WIRE 16 -1 (3475 4525)(3475 4475);
WIRE 16 -1 (3225 4525)(3475 4525);
WIRE 16 -1 (3475 4475)(3475 4400);
WIRE 16 -1 (3225 4475)(3475 4475);
WIRE 16 -1 (2375 5075)(1350 5075);
FORCEPROP 2 LAST SIG_NAME PVDDIO_P0_IMON1
J 0
(1415 5085);
DISPLAY 0.489362 (1415 5085);
WIRE 16 -1 (2375 4825)(1950 4825);
FORCEPROP 2 LAST SIG_NAME NC_PVDDIO_P0_DNC1
J 0
(1880 4835);
DISPLAY 0.489362 (1880 4835);
FORCEPROP 2 LASTPROP $XRERR UNIQUE?
J 0
(1710 4825);
DISPLAY 0.638298 (1710 4825);
PAINT MONO (1710 4825);
DISPLAY INVISIBLE (1710 4825);
WIRE 16 -1 (3225 2625)(4000 2625);
FORCEPROP 2 LAST SIG_NAME SW_PVDDIO_P0_BOOT2
J 0
(3390 2635);
DISPLAY 0.489362 (3390 2635);
FORCEPROP 2 LASTPROP $XRERR UNIQUE?
J 0
(3150 2635);
DISPLAY 0.638298 (3150 2635);
PAINT MONO (3150 2635);
DISPLAY INVISIBLE (3150 2635);
WIRE 16 -1 (3400 2925)(3400 2875);
WIRE 16 -1 (3225 2925)(3400 2925);
WIRE 16 -1 (3400 3450)(3400 2925);
WIRE 16 -1 (3400 2875)(3225 2875);
WIRE 16 -1 (3650 3450)(3400 3450);
WIRE 16 -1 (4150 3450)(3650 3450);
WIRE 16 -1 (3650 3300)(3650 3450);
WIRE 16 -1 (4150 3450)(4550 3450);
WIRE 16 -1 (4150 3300)(4150 3450);
WIRE 16 -1 (4550 3450)(4950 3450);
WIRE 16 -1 (4550 3450)(4550 3300);
WIRE 16 -1 (5425 3450)(4950 3450);
WIRE 16 -1 (4950 3300)(4950 3450);
WIRE 16 -1 (5425 3300)(5425 3450);
WIRE 16 -1 (5425 3525)(5425 3450);
WIRE 16 -1 (4300 4775)(4300 4425);
FORCEPROP 2 LAST SIG_NAME SW_PVDDIO_P0_SW1_RC
J 0
(4340 4560);
DISPLAY 0.489362 (4340 4560);
FORCEPROP 2 LASTPROP $XRERR UNIQUE?
J 0
(4100 4560);
DISPLAY 0.638298 (4100 4560);
PAINT MONO (4100 4560);
DISPLAY INVISIBLE (4100 4560);
WIRE 16 -1 (5625 6100)(5625 6225);
WIRE 16 -1 (5625 6225)(5950 6225);
WIRE 16 -1 (5625 6225)(5425 6225);
WIRE 16 -1 (5425 6300)(5425 6225);
WIRE 16 -1 (5225 6225)(5425 6225);
WIRE 16 -1 (5225 6225)(4800 6225);
WIRE 16 -1 (5225 6225)(5225 6100);
WIRE 16 -1 (4800 6075)(4800 6225);
WIRE 16 -1 (4400 6225)(4800 6225);
WIRE 16 -1 (4400 6225)(4400 6075);
WIRE 16 -1 (4000 6225)(4400 6225);
WIRE 16 -1 (4000 6225)(3575 6225);
WIRE 16 -1 (4000 6075)(4000 6225);
WIRE 16 -1 (3575 6225)(3400 6225);
WIRE 16 -1 (3575 6075)(3575 6225);
WIRE 16 -1 (3400 6225)(3400 5725);
WIRE 16 -1 (3400 5725)(3400 5675);
WIRE 16 -1 (3225 5725)(3400 5725);
WIRE 16 -1 (3400 5675)(3225 5675);
WIRE 16 -1 (7925 3175)(7925 3075);
WIRE 16 -1 (7525 3075)(7925 3075);
WIRE 16 -1 (7925 3075)(7925 2975);
WIRE 16 -1 (7525 3175)(7525 3075);
WIRE 16 -1 (7125 3075)(7525 3075);
WIRE 16 -1 (7125 3175)(7125 3075);
WIRE 17 273 (6800 2825)(8300 2825);
WIRE 17 273 (6800 2825)(6800 3700);
WIRE 17 273 (8300 3700)(8300 2825);
WIRE 17 273 (6800 3700)(8300 3700);
WIRE 16 -1 (4025 5425)(4825 5425);
FORCEPROP 2 LAST SIG_NAME SW_PVDDIO_P0_BOOT1_R
J 0
(4115 5435);
DISPLAY 0.489362 (4115 5435);
FORCEPROP 2 LASTPROP $XRERR UNIQUE?
J 0
(3875 5435);
DISPLAY 0.638298 (3875 5435);
PAINT MONO (3875 5435);
DISPLAY INVISIBLE (3875 5435);
WIRE 16 -1 (4825 5425)(4825 5400);
WIRE 16 -1 (5325 3975)(4050 3975);
WIRE 16 -1 (4050 4825)(4050 3975);
WIRE 16 -1 (3225 4825)(4050 4825);
FORCEPROP 2 LAST SIG_NAME PVDDIO_P0_VOS1
J 0
(3340 4850);
DISPLAY 0.489362 (3340 4850);
FORCEPROP 2 LASTPROP $XRERR UNIQUE?
J 0
(3100 4850);
DISPLAY 0.638298 (3100 4850);
PAINT MONO (3100 4850);
DISPLAY INVISIBLE (3100 4850);
WIRE 16 -1 (7275 1250)(7275 2275);
WIRE 16 -1 (7275 1250)(5525 1250);
WIRE 16 -1 (7625 2275)(7275 2275);
WIRE 16 -1 (6600 2275)(7275 2275);
WIRE 16 -1 (7625 2275)(8050 2275);
WIRE 16 -1 (7625 2275)(7625 2175);
WIRE 16 -1 (8050 2375)(8050 2275);
WIRE 16 -1 (8050 2175)(8050 2275);
WIRE 16 -1 (3225 1925)(3800 1925);
FORCEPROP 2 LAST SIG_NAME NC_PVDDIO_P0_GL2_2
J 0
(3415 1935);
DISPLAY 0.489362 (3415 1935);
FORCEPROP 2 LASTPROP $XRERR UNIQUE?
J 0
(3830 1925);
DISPLAY 0.638298 (3830 1925);
PAINT MONO (3830 1925);
DISPLAY INVISIBLE (3830 1925);
WIRE 16 -1 (3225 1975)(3800 1975);
FORCEPROP 2 LAST SIG_NAME NC_PVDDIO_P0_GL1_2
J 0
(3415 1985);
DISPLAY 0.489362 (3415 1985);
FORCEPROP 2 LASTPROP $XRERR UNIQUE?
J 0
(3830 1975);
DISPLAY 0.638298 (3830 1975);
PAINT MONO (3830 1975);
DISPLAY INVISIBLE (3830 1975);
WIRE 16 -1 (4300 1975)(4300 1675);
FORCEPROP 2 LAST SIG_NAME SW_PVDDIO_P0_SW2_RC
J 0
(4340 1785);
DISPLAY 0.489362 (4340 1785);
FORCEPROP 2 LASTPROP $XRERR UNIQUE?
J 0
(4100 1785);
DISPLAY 0.638298 (4100 1785);
PAINT MONO (4100 1785);
DISPLAY INVISIBLE (4100 1785);
WIRE 16 -1 (3475 1775)(3475 1825);
WIRE 16 -1 (3225 1775)(3475 1775);
WIRE 16 -1 (3475 1775)(3475 1725);
WIRE 16 -1 (3475 1825)(3225 1825);
WIRE 16 -1 (3475 1725)(3475 1675);
WIRE 16 -1 (3225 1725)(3475 1725);
WIRE 16 -1 (3475 1675)(3475 1600);
WIRE 16 -1 (3225 1675)(3475 1675);
WIRE 16 -1 (1950 2025)(2375 2025);
FORCEPROP 2 LAST SIG_NAME NC_PVDDIO_P0_DNC2
J 0
(1855 2035);
DISPLAY 0.489362 (1855 2035);
FORCEPROP 2 LASTPROP $XRERR UNIQUE?
J 0
(1710 2025);
DISPLAY 0.638298 (1710 2025);
PAINT MONO (1710 2025);
DISPLAY INVISIBLE (1710 2025);
WIRE 16 -1 (3225 2025)(3975 2025);
FORCEPROP 2 LAST SIG_NAME PVDDIO_P0_VOS2
J 0
(3415 2050);
DISPLAY 0.489362 (3415 2050);
FORCEPROP 2 LASTPROP $XRERR UNIQUE?
J 0
(3175 2050);
DISPLAY 0.638298 (3175 2050);
PAINT MONO (3175 2050);
DISPLAY INVISIBLE (3175 2050);
WIRE 16 -1 (3975 2025)(3975 1250);
WIRE 16 -1 (5325 1250)(3975 1250);
WIRE 16 -1 (5425 2900)(5425 2950);
WIRE 16 -1 (5425 3100)(5425 2950);
WIRE 16 -1 (5425 2950)(4950 2950);
WIRE 16 -1 (4950 3100)(4950 2950);
WIRE 16 -1 (4550 2950)(4950 2950);
WIRE 16 -1 (4550 3100)(4550 2950);
WIRE 16 -1 (4550 2950)(4150 2950);
WIRE 16 -1 (4150 3100)(4150 2950);
WIRE 16 -1 (3650 2950)(4150 2950);
WIRE 16 -1 (3650 3100)(3650 2950);
WIRE 16 -1 (7075 5075)(7075 3975);
WIRE 16 -1 (7175 5075)(7075 5075);
WIRE 16 -1 (7075 5075)(6425 5075);
WIRE 16 -1 (7075 3975)(5525 3975);
WIRE 16 -1 (7675 5075)(7175 5075);
WIRE 16 -1 (7175 4975)(7175 5075);
WIRE 16 -1 (7675 5075)(8100 5075);
WIRE 16 -1 (7675 5075)(7675 4975);
WIRE 16 -1 (8400 5075)(8100 5075);
WIRE 16 -1 (8100 4975)(8100 5075);
WIRE 16 -1 (8400 5150)(8400 5075);
WIRE 16 -1 (8400 5075)(8400 4975);
WIRE 16 -1 (4300 4975)(4300 5075);
WIRE 16 -1 (4300 5075)(5625 5075);
WIRE 16 -1 (3225 5075)(4300 5075);
FORCEPROP 2 LAST SIG_NAME SW_PVDDIO_P0_SW1
J 0
(3415 5085);
DISPLAY 0.489362 (3415 5085);
FORCEPROP 2 LASTPROP $XRERR UNIQUE?
J 0
(3175 5085);
DISPLAY 0.638298 (3175 5085);
PAINT MONO (3175 5085);
DISPLAY INVISIBLE (3175 5085);
WIRE 16 -1 (5625 5725)(5625 5900);
WIRE 16 -1 (5625 5725)(5425 5725);
WIRE 16 -1 (5425 5675)(5425 5725);
WIRE 16 -1 (5225 5725)(5425 5725);
WIRE 16 -1 (5225 5900)(5225 5725);
WIRE 16 -1 (5225 5725)(4800 5725);
WIRE 16 -1 (4800 5875)(4800 5725);
WIRE 16 -1 (4400 5725)(4800 5725);
WIRE 16 -1 (4400 5875)(4400 5725);
WIRE 16 -1 (4400 5725)(4000 5725);
WIRE 16 -1 (4000 5875)(4000 5725);
WIRE 16 -1 (3575 5725)(4000 5725);
WIRE 16 -1 (3575 5875)(3575 5725);
DOT 1 (2225 2175);
DOT 1 (7525 3075);
DOT 1 (5425 5725);
DOT 1 (1150 2850);
DOT 1 (1150 3450);
DOT 1 (1500 3450);
DOT 1 (2225 2625);
DOT 1 (3475 1675);
DOT 1 (3475 1725);
DOT 1 (3475 1775);
DOT 1 (3400 2925);
DOT 1 (3650 3450);
DOT 1 (3475 4475);
DOT 1 (3475 4525);
DOT 1 (3475 4575);
DOT 1 (1250 5525);
DOT 1 (1250 6125);
DOT 1 (1600 6125);
DOT 1 (2225 4975);
DOT 1 (2225 5425);
DOT 1 (3400 5725);
DOT 1 (4000 5725);
DOT 1 (3575 6225);
DOT 1 (4000 6225);
DOT 1 (4300 2275);
DOT 1 (4150 2950);
DOT 1 (4550 2950);
DOT 1 (4150 3450);
DOT 1 (4550 3450);
DOT 1 (4950 2950);
DOT 1 (4950 3450);
DOT 1 (5425 2950);
DOT 1 (5425 3450);
DOT 1 (7275 2275);
DOT 1 (7625 2275);
DOT 1 (8050 1850);
DOT 1 (8050 2275);
DOT 1 (7675 4650);
DOT 1 (8100 4650);
DOT 1 (4300 5075);
DOT 1 (4400 5725);
DOT 1 (4400 6225);
DOT 1 (4800 6225);
DOT 1 (5225 5725);
DOT 1 (5225 6225);
DOT 1 (5425 6225);
DOT 1 (5625 6225);
DOT 1 (7075 5075);
DOT 1 (7175 5075);
DOT 1 (7675 5075);
DOT 1 (8100 5075);
DOT 1 (8400 4650);
DOT 1 (8400 5075);
DOT 1 (7925 3500);
DOT 1 (7925 3075);
DOT 1 (7525 3500);
DOT 1 (4800 5725);
FORCENOTE
PR98,PR97,PR106,PR105 = CS00002JB38
(-325 625) 0;
DISPLAY LEFT (-325 625);
DISPLAY 1.021277 (-325 625);
PAINT WHITE (-325 625);
FORCENOTE
PR101,PR102,PR110,PR109 = CS00002JB38
(-325 850) 0;
DISPLAY LEFT (-325 850);
DISPLAY 1.021277 (-325 850);
PAINT WHITE (-325 850);
FORCENOTE
PR103,PR104,PR111,PR112 = EMPTY
(-325 775) 0;
DISPLAY LEFT (-325 775);
DISPLAY 1.021277 (-325 775);
PAINT WHITE (-325 775);
FORCENOTE
PC145_7,PC146_8,PC175_9,PC176_10 = EMPTY
(-325 700) 0;
DISPLAY LEFT (-325 700);
DISPLAY 1.021277 (-325 700);
PAINT WHITE (-325 700);
FORCENOTE
3RD SOURCE:MPS BOM
(-325 550) 0;
DISPLAY LEFT (-325 550);
DISPLAY 1.021277 (-325 550);
PAINT WHITE (-325 550);
FORCENOTE
PU17,PU18,PU19,PU20=AL087000A02/MP87000GMJTH-C06A-Z
(-325 475) 0;
DISPLAY LEFT (-325 475);
DISPLAY 1.021277 (-325 475);
PAINT WHITE (-325 475);
FORCENOTE
PC145_7,PC146_8,PC175_9,PC176_10=EMPTY
(-325 400) 0;
DISPLAY LEFT (-325 400);
DISPLAY 1.021277 (-325 400);
PAINT WHITE (-325 400);
FORCENOTE
PR103,PR104,PR111,PR112=EMPTY
(-325 325) 0;
DISPLAY LEFT (-325 325);
DISPLAY 1.021277 (-325 325);
PAINT WHITE (-325 325);
FORCENOTE
PR101,PR102,PR109,PR110=CS00002JB38
(-325 250) 0;
DISPLAY LEFT (-325 250);
DISPLAY 1.021277 (-325 250);
PAINT WHITE (-325 250);
FORCENOTE
PU17,PU18,PU19,PU20 = AL021590000/TDA21590
(-325 925) 0;
DISPLAY LEFT (-325 925);
DISPLAY 1.021277 (-325 925);
PAINT WHITE (-325 925);
FORCENOTE
PU17,PU18,PU19,PU20 =AL099390004/ISL99390FRZ-TR5935
(-325 1150) 0;
DISPLAY LEFT (-325 1150);
DISPLAY 1.021277 (-325 1150);
PAINT WHITE (-325 1150);
FORCENOTE
3RD=CC72204MD03
(5550 5475) 0;
DISPLAY LEFT (5550 5475);
DISPLAY 0.638298 (5550 5475);
PAINT WHITE (5550 5475);
FORCENOTE
2ND=CC72204MD01
(5550 5525) 0;
DISPLAY LEFT (5550 5525);
DISPLAY 0.638298 (5550 5525);
PAINT WHITE (5550 5525);
FORCENOTE
PVDDIO_P0_PHASE2
(2525 3350) 0;
DISPLAY LEFT (2525 3350);
DISPLAY 1.021277 (2525 3350);
PAINT WHITE (2525 3350);
FORCENOTE
2ND=CH747LM8822
(7350 2875) 0;
DISPLAY LEFT (7350 2875);
DISPLAY 0.638298 (7350 2875);
PAINT WHITE (7350 2875);
FORCENOTE
7.3*4.3*1.9
(7350 2925) 0;
DISPLAY LEFT (7350 2925);
DISPLAY 0.638298 (7350 2925);
PAINT WHITE (7350 2925);
FORCENOTE
ESR=4.5M OHM
(7350 2975) 0;
DISPLAY LEFT (7350 2975);
DISPLAY 0.638298 (7350 2975);
PAINT WHITE (7350 2975);
FORCENOTE
8*11.5
(5550 5575) 0;
DISPLAY LEFT (5550 5575);
DISPLAY 0.638298 (5550 5575);
PAINT WHITE (5550 5575);
FORCENOTE
IRIPPLE:4.65A
(5550 5625) 0;
DISPLAY LEFT (5550 5625);
DISPLAY 0.638298 (5550 5625);
PAINT WHITE (5550 5625);
FORCENOTE
ESR=16M OHM
(5550 5675) 0;
DISPLAY LEFT (5550 5675);
DISPLAY 0.638298 (5550 5675);
PAINT WHITE (5550 5675);
FORCENOTE
3RD=CVA50^0MZ08
(5925 5900) 0;
DISPLAY LEFT (5925 5900);
DISPLAY 0.638298 (5925 5900);
PAINT WHITE (5925 5900);
FORCENOTE
2ND=CVA50^0MZ07
(5925 5950) 0;
DISPLAY LEFT (5925 5950);
DISPLAY 0.638298 (5925 5950);
PAINT WHITE (5925 5950);
FORCENOTE
DCR=0.09M OHM
(5925 6000) 0;
DISPLAY LEFT (5925 6000);
DISPLAY 0.638298 (5925 6000);
PAINT WHITE (5925 6000);
FORCENOTE
PVDDIO_P0_PHASE1
(2525 6175) 0;
DISPLAY LEFT (2525 6175);
DISPLAY 1.021277 (2525 6175);
PAINT WHITE (2525 6175);
FORCENOTE
PG2292.500HLT
(5925 6150) 0;
DISPLAY LEFT (5925 6150);
DISPLAY 0.638298 (5925 6150);
PAINT WHITE (5925 6150);
FORCENOTE
ISAT:70A@100C
(5925 6100) 0;
DISPLAY LEFT (5925 6100);
DISPLAY 0.638298 (5925 6100);
PAINT WHITE (5925 6100);
FORCENOTE
6.0*6.1*7.0
(5925 6050) 0;
DISPLAY LEFT (5925 6050);
DISPLAY 0.638298 (5925 6050);
PAINT WHITE (5925 6050);
FORCENOTE
2ND=CV+15^0TZ01
(6600 2350) 0;
DISPLAY LEFT (6600 2350);
DISPLAY 0.638298 (6600 2350);
PAINT WHITE (6600 2350);
FORCENOTE
DCR=2-3,0.27M OHM
(6600 2400) 0;
DISPLAY LEFT (6600 2400);
DISPLAY 0.638298 (6600 2400);
PAINT WHITE (6600 2400);
FORCENOTE
DCR=1-4,0.105M OHM
(6600 2450) 0;
DISPLAY LEFT (6600 2450);
DISPLAY 0.638298 (6600 2450);
PAINT WHITE (6600 2450);
FORCENOTE
11.0*7.5*12.5
(6600 2500) 0;
DISPLAY LEFT (6600 2500);
DISPLAY 0.638298 (6600 2500);
PAINT WHITE (6600 2500);
FORCENOTE
ISAT:70A@100C
(6600 2550) 0;
DISPLAY LEFT (6600 2550);
DISPLAY 0.638298 (6600 2550);
PAINT WHITE (6600 2550);
FORCENOTE
PGL6303.151HLT
(6600 2600) 0;
DISPLAY LEFT (6600 2600);
DISPLAY 0.638298 (6600 2600);
PAINT WHITE (6600 2600);
FORCENOTE
PGL6303.151HLT
(6450 5400) 0;
DISPLAY LEFT (6450 5400);
DISPLAY 0.638298 (6450 5400);
PAINT WHITE (6450 5400);
FORCENOTE
ISAT:70A@100C
(6450 5350) 0;
DISPLAY LEFT (6450 5350);
DISPLAY 0.638298 (6450 5350);
PAINT WHITE (6450 5350);
FORCENOTE
11.0*7.5*12.5
(6450 5300) 0;
DISPLAY LEFT (6450 5300);
DISPLAY 0.638298 (6450 5300);
PAINT WHITE (6450 5300);
FORCENOTE
DCR=1-4,0.105M OHM
(6450 5250) 0;
DISPLAY LEFT (6450 5250);
DISPLAY 0.638298 (6450 5250);
PAINT WHITE (6450 5250);
FORCENOTE
DCR=2-3,0.27M OHM
(6450 5200) 0;
DISPLAY LEFT (6450 5200);
DISPLAY 0.638298 (6450 5200);
PAINT WHITE (6450 5200);
FORCENOTE
2ND=CV+15^0TZ01
(6450 5150) 0;
DISPLAY LEFT (6450 5150);
DISPLAY 0.638298 (6450 5150);
PAINT WHITE (6450 5150);
FORCENOTE
BOM NOTE
(-325 1300) 0;
DISPLAY LEFT (-325 1300);
DISPLAY 1.021277 (-325 1300);
PAINT WHITE (-325 1300);
FORCENOTE
MAIN SOURCE:RENESAS BOM
(-325 1225) 0;
DISPLAY LEFT (-325 1225);
DISPLAY 1.021277 (-325 1225);
PAINT WHITE (-325 1225);
FORCENOTE
2ND SOURCE:INFENEON BOM
(-325 1000) 0;
DISPLAY LEFT (-325 1000);
DISPLAY 1.021277 (-325 1000);
PAINT WHITE (-325 1000);
QUIT
